G04 ================== begin FILE IDENTIFICATION RECORD ==================*
G04 Layout Name:  D:/<user>/Wistron_project/16342-2/gbr/16342-2.brd*
G04 Film Name:    L3*
G04 File Format:  Gerber RS274X*
G04 File Origin:  Cadence Allegro 16.5-S056*
G04 Origin Date:  Mon Aug 07 11:24:41 2017*
G04 *
G04 Layer:  VIA CLASS/L3*
G04 Layer:  PIN/L3*
G04 Layer:  ETCH/L3*
G04 Layer:  DRAWING FORMAT/LAYER_PCB_STORY*
G04 Layer:  DRAWING FORMAT/LAYER_L3*
G04 *
G04 Offset:    (0.00 0.00)*
G04 Mirror:    No*
G04 Mode:      Positive*
G04 Rotation:  0*
G04 FullContactRelief:  No*
G04 UndefLineWidth:     6.00*
G04 ================== end FILE IDENTIFICATION RECORD ====================*
%FSLAX35Y35*MOIN*%
%IR0*IPPOS*OFA0.00000B0.00000*MIA0B0*SFA1.00000B1.00000*%
%ADD12C,.02*%
%ADD15C,.03*%
%ADD14C,.022*%
%ADD16C,.026*%
%ADD13C,.018*%
%ADD11C,.028*%
%ADD10C,.056*%
%ADD17C,.01*%
%ADD18C,.012*%
%ADD19C,.04*%
%ADD20C,.015*%
%ADD21C,.025*%
%ADD22C,.004*%
%ADD23C,.005*%
%ADD24C,.006*%
%ADD25C,.007*%
%ADD26C,.0035*%
%ADD27C,.0055*%
%ADD28C,.00499*%
%ADD31C,.04404*%
%ADD30O,.15002X.21302*%
%ADD29O,.15004X.21304*%
G75*
%LPD*%
G75*
G36*
G01X6002Y722992D02*
X23394Y757778D01*
X38071D01*
G02X38288Y757043I0J-400D01*
G03X33556Y752780I10926J-16885D01*
G01X26483D01*
X11125Y722062D01*
X10896D01*
X10750Y721916D01*
Y721708D01*
X10896Y721562D01*
X11000D01*
Y11000D01*
X109197D01*
Y40396D01*
X109343Y40437D01*
G03Y48147I-1075J3855D01*
G01X109197Y48188D01*
Y428627D01*
X114196D01*
Y6002D01*
X6002D01*
Y722992D01*
G37*
G36*
G01X64870Y752780D02*
G03X60138Y757043I-15658J-12622D01*
G02X60355Y757778I217J335D01*
G01X353031D01*
G02X353248Y757043I0J-400D01*
G03X348516Y752780I10926J-16885D01*
G01X64870D01*
G37*
G36*
G01X136414Y522899D02*
X137269Y523754D01*
Y526822D01*
X137960Y527513D01*
X140276D01*
X140774Y527015D01*
Y520391D01*
X139597Y519214D01*
X138125D01*
X137854Y518943D01*
Y509354D01*
X137427Y508927D01*
X133948D01*
X133554Y509321D01*
Y511946D01*
X132877Y512623D01*
X123023D01*
X122872Y512774D01*
Y522720D01*
X123051Y522899D01*
X136414D01*
G37*
G36*
G01X130263Y650300D02*
X130833Y650870D01*
X135496D01*
X136234Y650132D01*
Y646698D01*
X135303Y645767D01*
X130808D01*
X130263Y646312D01*
Y650300D01*
G37*
G36*
G01X212354Y584942D02*
X211164Y586132D01*
X211195Y586244D01*
G03X210523Y587838I-1353J368D01*
G02Y588538I194J350D01*
G03X211068Y589082I-680J1226D01*
G02X211767I350J-194D01*
G03X213389Y588419I1225J682D01*
G01X213503Y588453D01*
X214742Y587214D01*
Y586700D01*
G03Y586528I1399J-86D01*
G01Y586100D01*
X213585Y584942D01*
X212354D01*
G37*
G36*
G01X207917Y590444D02*
G03X206323Y591116I-1226J-681D01*
G01X206211Y591085D01*
X205944Y591352D01*
Y594037D01*
X206506Y594600D01*
X207356D01*
X208531Y593425D01*
X208497Y593311D01*
G03X209160Y591687I1344J-399D01*
G02Y590988I-194J-350D01*
G03X208617Y590444I683J-1224D01*
G02X207917I-350J194D01*
G37*
G36*
G01X166646Y581392D02*
G03X165276Y581635I-898J-1077D01*
G01X165157Y581593D01*
X164192Y582558D01*
Y583514D01*
X164348Y583549D01*
G03X167148Y586233I-835J3673D01*
G03X167155Y586256I-1384J434D01*
G02X167542Y586258I194J-49D01*
G03X168217Y585389I1356J356D01*
G02Y584689I-194J-350D01*
G03X168216Y582239I681J-1225D01*
G02Y581540I-194J-350D01*
G03X168000Y581392I681J-1226D01*
G01X166646D01*
G37*
G36*
G01X169796D02*
G03X169580Y581540I-897J-1078D01*
G02Y582239I194J350D01*
G03X169579Y584689I-682J1225D01*
G02Y585389I194J350D01*
G03X167542Y586970I-681J1225D01*
G02X167155Y586972I-193J51D01*
G03X166996Y587355I-1406J-359D01*
G01Y589023D01*
G03X167045Y590415I-1248J741D01*
G01X166980Y590544D01*
X167841Y591405D01*
X176282D01*
X176942Y590745D01*
Y582583D01*
X175751Y581392D01*
X169796D01*
G37*
G36*
G01X197200Y582700D02*
X195900Y584000D01*
Y587200D01*
X196063Y587362D01*
X201338D01*
X201700Y587000D01*
Y583900D01*
X200500Y582700D01*
X197200D01*
G37*
G36*
G01X282500Y620500D02*
X282608Y620392D01*
Y610309D01*
X282501Y610202D01*
X277105D01*
X276559Y609656D01*
Y606333D01*
X276313Y606087D01*
X273676D01*
X273233Y606530D01*
Y609524D01*
X272653Y610104D01*
X267817D01*
X267675Y610246D01*
Y623671D01*
X268005Y624001D01*
X271335D01*
X271640Y623696D01*
Y621188D01*
X272328Y620500D01*
X282500D01*
G37*
G36*
G01X914197Y721812D02*
X898714Y752780D01*
X891641D01*
G03X886909Y757043I-15658J-12622D01*
G02X887126Y757778I217J335D01*
G01X901803D01*
X919196Y722993D01*
Y6002D01*
X293522D01*
Y141799D01*
X298520D01*
Y11000D01*
X370472D01*
X374417Y7054D01*
X578861D01*
X582806Y11000D01*
X914197D01*
Y721812D01*
G37*
G36*
G01X357481Y643529D02*
X357210Y643800D01*
Y650300D01*
X356976Y650534D01*
X354764D01*
X354045Y651253D01*
Y653597D01*
X354525Y654077D01*
X372016D01*
X372216Y653877D01*
Y647523D01*
X372488Y647251D01*
X374854D01*
X375384Y646720D01*
Y643990D01*
X374924Y643529D01*
X357481D01*
G37*
G36*
G01X397268Y702285D02*
Y719900D01*
X402266D01*
Y702285D01*
X397268D01*
G37*
G36*
G01X397143Y722062D02*
X381785Y752780D01*
X379830D01*
X379770Y752854D01*
G03X375098Y757043I-15598J-12696D01*
G02X375315Y757778I217J335D01*
G01X384874D01*
X402266Y722992D01*
Y722062D01*
X397143D01*
G37*
G36*
G01X579110Y188976D02*
G02X559273Y177976I-12969J0D01*
G01X554772D01*
Y182974D01*
X560897D01*
G03X574112Y188976I5245J6002D01*
G01Y293359D01*
G02X574790Y293647I400J0D01*
G03X579110Y290523I13007J13438D01*
G01Y188976D01*
G37*
G36*
G01X574112Y320815D02*
Y459656D01*
G02X574824Y459905I400J0D01*
G03X579110Y455901I15726J12537D01*
G01Y323651D01*
G03X574790Y320527I8687J-16562D01*
G02X574112Y320815I-278J288D01*
G37*
G36*
G01Y589134D02*
X591504Y623920D01*
X842520D01*
G03X852458Y633858I0J9938D01*
G01Y757778D01*
X864842D01*
G02X865059Y757043I0J-400D01*
G03X860387Y752854I10926J-16885D01*
G01X860327Y752780D01*
X857457D01*
Y747982D01*
X857441Y747944D01*
G03X857457Y732333I18543J-7787D01*
G01Y633858D01*
G02X842520Y618921I-14937J0D01*
G01X594593D01*
X579110Y587953D01*
Y488981D01*
G03X574824Y484977I11440J-16541D01*
G02X574112Y485226I-312J249D01*
G01Y589134D01*
G37*
G36*
G01X663288Y390339D02*
X692241Y419292D01*
X791636D01*
X795828Y415100D01*
Y396112D01*
X804210Y387730D01*
Y338455D01*
X834030Y308635D01*
Y57239D01*
X824229Y47438D01*
X706878D01*
X685728Y68588D01*
Y131778D01*
X663288Y154218D01*
Y390339D01*
G37*
%LPC*%
G75*
G54D31*
X713200Y387700D03*
X718300D03*
X801200Y386700D03*
X796100D03*
G54D30*
X706299Y201771D03*
Y83661D03*
G54D29*
X804724Y201772D03*
Y83661D03*
%LPD*%
G75*
G54D10*
X61024Y34449D03*
X33464D03*
X108268Y44292D03*
X80708D03*
G54D20*
G01X182100Y601757D02*
X190944Y592913D01*
G54D11*
X66435Y8514D03*
X61435D03*
X56435D03*
X51435D03*
X46435D03*
X41435D03*
X36435D03*
X31435D03*
X26435D03*
X21435D03*
X16435D03*
X8514Y10593D03*
Y15593D03*
Y20593D03*
Y25593D03*
Y30593D03*
Y35593D03*
Y40593D03*
Y45593D03*
Y50593D03*
Y55593D03*
Y60593D03*
Y65593D03*
Y70593D03*
Y75593D03*
Y80593D03*
Y85593D03*
Y90593D03*
Y95593D03*
Y100593D03*
Y105593D03*
Y110593D03*
Y115593D03*
Y120593D03*
Y125593D03*
Y130593D03*
Y135593D03*
Y140593D03*
Y145593D03*
Y150593D03*
Y155593D03*
Y160593D03*
Y165593D03*
Y170593D03*
Y175593D03*
Y180593D03*
Y185593D03*
Y190593D03*
Y195593D03*
Y200593D03*
Y205593D03*
Y210593D03*
Y215593D03*
Y220593D03*
Y225593D03*
Y230593D03*
Y235593D03*
Y240593D03*
Y245593D03*
Y250593D03*
Y255593D03*
Y260593D03*
Y265593D03*
Y270593D03*
Y275593D03*
Y280593D03*
Y285593D03*
Y290593D03*
Y295593D03*
Y300593D03*
Y305593D03*
Y310593D03*
Y315593D03*
Y320593D03*
Y325593D03*
Y330593D03*
Y335593D03*
Y340593D03*
Y345593D03*
Y350593D03*
Y355593D03*
Y360593D03*
Y365593D03*
Y370593D03*
Y375593D03*
Y380593D03*
Y385593D03*
Y390593D03*
Y395593D03*
Y400593D03*
Y405593D03*
Y410593D03*
Y415593D03*
Y420593D03*
Y425593D03*
Y430593D03*
Y435593D03*
Y440593D03*
Y445593D03*
Y450593D03*
Y455593D03*
Y460593D03*
Y465593D03*
Y470593D03*
Y475593D03*
Y480593D03*
Y485593D03*
Y490593D03*
Y495593D03*
Y500593D03*
Y505593D03*
Y510593D03*
Y515593D03*
Y520593D03*
Y525593D03*
Y530593D03*
Y535593D03*
Y540593D03*
Y545593D03*
Y550593D03*
Y555593D03*
Y560593D03*
Y565593D03*
Y570593D03*
Y575593D03*
Y580593D03*
Y585593D03*
Y590593D03*
Y595593D03*
Y600593D03*
Y605593D03*
Y610593D03*
Y615593D03*
Y620593D03*
Y625593D03*
Y630593D03*
Y635593D03*
Y640593D03*
Y645593D03*
Y650593D03*
Y655593D03*
Y660593D03*
Y665593D03*
Y670593D03*
Y675593D03*
Y680593D03*
Y685593D03*
Y690593D03*
Y695593D03*
Y700593D03*
Y705593D03*
Y710593D03*
Y715593D03*
Y720593D03*
X9942Y725256D03*
X12178Y729728D03*
X14414Y734200D03*
X16650Y738672D03*
X18886Y743144D03*
X21122Y747617D03*
X23358Y752089D03*
X111683Y63266D03*
Y58266D03*
Y23266D03*
Y18266D03*
Y13266D03*
X111435Y8514D03*
X106435D03*
X101435D03*
X96435D03*
X91435D03*
X86435D03*
X81435D03*
X76435D03*
X71435D03*
X111683Y118266D03*
Y113266D03*
Y108266D03*
Y103266D03*
Y98266D03*
Y93266D03*
Y88266D03*
Y83266D03*
Y78266D03*
Y73266D03*
Y68266D03*
Y203266D03*
Y198266D03*
Y193266D03*
Y188266D03*
Y183266D03*
Y178266D03*
Y173266D03*
Y168266D03*
Y163266D03*
Y158266D03*
Y153266D03*
Y148266D03*
Y278266D03*
Y273266D03*
Y268266D03*
Y263266D03*
Y258266D03*
Y253266D03*
Y248266D03*
Y243266D03*
Y238266D03*
Y233266D03*
Y228266D03*
Y223266D03*
Y218266D03*
Y213266D03*
Y208266D03*
Y348266D03*
Y343266D03*
Y338266D03*
Y333266D03*
Y328266D03*
Y323266D03*
Y318266D03*
Y313266D03*
Y308266D03*
Y303266D03*
Y298266D03*
Y293266D03*
Y288266D03*
Y283266D03*
Y418266D03*
Y413266D03*
Y408266D03*
Y403266D03*
Y398266D03*
Y393266D03*
Y388266D03*
Y383266D03*
Y378266D03*
Y373266D03*
Y368266D03*
Y363266D03*
Y358266D03*
Y353266D03*
X103940Y635460D03*
X81549Y675547D03*
X134223Y691027D03*
X76395Y755266D03*
X81395D03*
X86395D03*
X91395D03*
X96395D03*
X101395D03*
X106395D03*
X111395D03*
X116395D03*
X121395D03*
X126395D03*
X131395D03*
X136395D03*
X141395D03*
X146395D03*
X151395D03*
X156395D03*
X161395D03*
X166395D03*
X171395D03*
X176395D03*
X181395D03*
X186395D03*
X191395D03*
X196395D03*
X201395D03*
X206395D03*
X211395D03*
X216395D03*
X221395D03*
X226395D03*
X231395D03*
X236395D03*
X241395D03*
X246395D03*
X251395D03*
X256395D03*
X261395D03*
X266395D03*
X271395D03*
X276395D03*
X281395D03*
X330546Y8514D03*
X325546D03*
X320546D03*
X315546D03*
X310546D03*
X305546D03*
X300546D03*
X296034Y9002D03*
Y14002D03*
Y19002D03*
Y24002D03*
Y29002D03*
Y34002D03*
Y39002D03*
Y44002D03*
Y49002D03*
Y54002D03*
Y59002D03*
Y64002D03*
Y69002D03*
Y74002D03*
Y79002D03*
Y84002D03*
Y89002D03*
Y94002D03*
Y99002D03*
Y104002D03*
Y109002D03*
Y114002D03*
Y119002D03*
Y124002D03*
Y129002D03*
Y134002D03*
Y139002D03*
X323492Y214234D03*
X305862Y210014D03*
X286395Y755266D03*
X291395D03*
X296395D03*
X301395D03*
X306395D03*
X311395D03*
X316395D03*
X321395D03*
X326395D03*
X331395D03*
X336395D03*
X399754Y706071D03*
X389168Y743572D03*
X391404Y739100D03*
X393640Y734628D03*
X395876Y730156D03*
X398112Y725684D03*
X399754Y716071D03*
Y711071D03*
X567700Y28240D03*
X576624Y193205D03*
Y198205D03*
Y203205D03*
Y208205D03*
Y213205D03*
Y223205D03*
Y228205D03*
Y233205D03*
Y238205D03*
Y243205D03*
Y248205D03*
Y253205D03*
Y258205D03*
Y263205D03*
Y268205D03*
Y273205D03*
Y278205D03*
Y333205D03*
Y338205D03*
Y343205D03*
Y348205D03*
Y353205D03*
Y358205D03*
Y363205D03*
Y368205D03*
Y373205D03*
Y378205D03*
Y383205D03*
Y388205D03*
Y393205D03*
Y398205D03*
Y403205D03*
Y408205D03*
Y413205D03*
Y418205D03*
Y423205D03*
Y428205D03*
Y433205D03*
Y438205D03*
Y443205D03*
Y448205D03*
Y498205D03*
Y503205D03*
Y508205D03*
Y513205D03*
Y518205D03*
Y523205D03*
Y528205D03*
Y533205D03*
Y538205D03*
Y543205D03*
Y548205D03*
Y553205D03*
Y558205D03*
Y563205D03*
Y568205D03*
Y573205D03*
Y578205D03*
Y583205D03*
Y588205D03*
X578710Y592712D03*
X580946Y597184D03*
X583182Y601656D03*
X585418Y606129D03*
X587654Y610601D03*
X635975Y621407D03*
X640975D03*
X715546Y8514D03*
X710546D03*
X705546D03*
X700546D03*
X695546D03*
X700065Y135985D03*
Y125985D03*
Y115985D03*
X710065D03*
Y125985D03*
Y135985D03*
X649590Y114036D03*
X700065Y155985D03*
X710065D03*
Y145985D03*
X696159Y225829D03*
X698909Y278104D03*
X700065Y265985D03*
Y255985D03*
Y245985D03*
Y235985D03*
X710065D03*
Y245985D03*
Y255985D03*
Y265985D03*
X709625Y275991D03*
X710065Y325985D03*
Y315985D03*
X711574Y285985D03*
X708307Y295429D03*
X710065Y305985D03*
Y335985D03*
Y345985D03*
X700065Y385985D03*
Y395985D03*
Y405985D03*
Y415985D03*
X710065Y375985D03*
Y355985D03*
Y365985D03*
X689875Y464586D03*
X698275Y438305D03*
X645975Y621407D03*
X650975D03*
X655975D03*
X660975D03*
X665975D03*
X670975D03*
X675975D03*
X680975D03*
X685975D03*
X690975D03*
X695975D03*
X700975D03*
X705975D03*
X710975D03*
X715975D03*
X785546Y8514D03*
X780546D03*
X775546D03*
X770546D03*
X765546D03*
X760546D03*
X755546D03*
X750546D03*
X745546D03*
X740546D03*
X735546D03*
X730546D03*
X725546D03*
X720546D03*
X770065Y55985D03*
Y65985D03*
Y75985D03*
X750065Y85985D03*
X770065D03*
X760065D03*
X740065D03*
X730065Y95985D03*
X760065D03*
X780065D03*
X770065D03*
Y105985D03*
X780065D03*
Y115985D03*
X730065Y135985D03*
Y125985D03*
Y115985D03*
Y105985D03*
X750065Y95985D03*
X740065D03*
X750065Y105985D03*
X760065D03*
X740065D03*
X750065Y115985D03*
X760065D03*
X770065D03*
X740065D03*
X750065Y125985D03*
X760065D03*
X770065D03*
X780065D03*
X740065D03*
X750065Y135985D03*
X760065D03*
X770065D03*
X780065D03*
X740065D03*
X720065Y105985D03*
Y115985D03*
Y125985D03*
Y135985D03*
Y155985D03*
X780065D03*
X730065D03*
Y145985D03*
X750065D03*
X760065D03*
X770065D03*
X780065D03*
X740065D03*
X750065Y155985D03*
X760065D03*
X770065D03*
X740065D03*
X750065Y165985D03*
X760065D03*
X770065D03*
X740065D03*
X750065Y175985D03*
X760065D03*
X770065D03*
X740065D03*
X750065Y185985D03*
X760065D03*
X770065D03*
X740065D03*
X750065Y195985D03*
X760065D03*
X770065D03*
X740065D03*
X750065Y205985D03*
X760065D03*
X770065D03*
X740065D03*
X720065Y145985D03*
X730065Y215985D03*
X773469Y277001D03*
X780065Y275985D03*
X787817Y275879D03*
X750065Y215985D03*
X760065D03*
X770065D03*
X780065D03*
X740065D03*
X780065Y265985D03*
Y255985D03*
Y245985D03*
Y235985D03*
Y225985D03*
X770065Y265985D03*
Y255985D03*
Y245985D03*
Y235985D03*
Y225985D03*
X763133Y275881D03*
X759790Y263326D03*
X760065Y255985D03*
Y245985D03*
Y235985D03*
Y225985D03*
X750065Y275985D03*
Y265985D03*
Y255985D03*
Y245985D03*
Y235985D03*
Y225985D03*
X741608Y277171D03*
X740065Y265985D03*
Y255985D03*
Y245985D03*
Y235985D03*
Y225985D03*
X730830Y276087D03*
X730065Y265985D03*
Y255985D03*
X731766Y246017D03*
X730065Y235985D03*
X730190Y223549D03*
X720237Y223228D03*
X720065Y235985D03*
X721766Y246017D03*
X720065Y255985D03*
Y265985D03*
X718617Y275736D03*
X770065Y335985D03*
X760065D03*
X720065Y325985D03*
X760065D03*
X750065D03*
X740065D03*
X730065D03*
X720065Y315985D03*
X780065Y285985D03*
X770065D03*
X760065D03*
X750065Y295985D03*
X760065D03*
X770065D03*
X780065D03*
Y305985D03*
Y315985D03*
Y325985D03*
Y335985D03*
Y345985D03*
X770065Y305985D03*
Y315985D03*
Y325985D03*
Y345985D03*
X760065Y305985D03*
Y315985D03*
Y345985D03*
X750065Y305985D03*
Y315985D03*
Y335985D03*
Y345985D03*
X740065Y305985D03*
Y315985D03*
Y335985D03*
Y345985D03*
X730065D03*
Y335985D03*
Y315985D03*
X752500Y286000D03*
X740065Y295985D03*
X741000Y286000D03*
X730065Y305985D03*
X729486Y296094D03*
X729294Y285987D03*
X721574Y285985D03*
X719049Y296011D03*
X720065Y305985D03*
Y335985D03*
Y345985D03*
X750065Y415985D03*
X760065D03*
X770065D03*
X780065D03*
X730065D03*
X740065D03*
X750065Y405985D03*
X760065D03*
X770065D03*
X780065D03*
X730065D03*
X740065D03*
X780065Y395985D03*
X770065D03*
X760065D03*
X750065D03*
X740065D03*
X730065D03*
X720065Y375985D03*
X730065Y365985D03*
Y375985D03*
Y385985D03*
X750065D03*
X760065D03*
X770065D03*
X780065D03*
X740065D03*
X750065Y375985D03*
X760065D03*
X770065D03*
X780065D03*
X740065D03*
X750065Y365985D03*
X760065D03*
X770065D03*
X780065D03*
X740065D03*
X780065Y355985D03*
X770065D03*
X760065D03*
X750065D03*
X740065D03*
X730065D03*
X720065D03*
Y365985D03*
X720975Y621407D03*
X725975D03*
X730975D03*
X735975D03*
X740975D03*
X745975D03*
X750975D03*
X755975D03*
X760975D03*
X765975D03*
X770975D03*
X775975D03*
X780975D03*
X785975D03*
X850546Y8514D03*
X845546D03*
X840546D03*
X835546D03*
X830546D03*
X825546D03*
X820546D03*
X815546D03*
X810546D03*
X805546D03*
X800546D03*
X795546D03*
X790546D03*
X820065Y105985D03*
Y135985D03*
Y125985D03*
Y115985D03*
X810065Y135985D03*
Y125985D03*
Y115985D03*
X790065Y105985D03*
X800065Y115985D03*
X790065D03*
Y125985D03*
X800065D03*
Y135985D03*
X790065D03*
X820065Y155985D03*
X810065D03*
X800065D03*
X790065D03*
X820065Y145985D03*
X810065D03*
X790065D03*
X800065D03*
X820313Y276188D03*
X810065Y275985D03*
X800065D03*
X820065Y265985D03*
Y255985D03*
Y245985D03*
Y235985D03*
Y225985D03*
X810065Y265985D03*
Y255985D03*
Y245985D03*
Y235985D03*
X800065Y265985D03*
Y255985D03*
Y245985D03*
Y235985D03*
X790065Y265985D03*
Y255985D03*
Y245985D03*
Y235985D03*
Y225985D03*
X820065Y305985D03*
Y295985D03*
Y285985D03*
X810065Y295985D03*
Y285985D03*
X800065D03*
X790065D03*
Y295985D03*
X800065D03*
X810065Y305985D03*
X810000Y314000D03*
X810065Y325985D03*
X800065Y305985D03*
Y315985D03*
Y325985D03*
Y335985D03*
Y345985D03*
X790065Y305985D03*
Y315985D03*
Y325985D03*
X791500Y336000D03*
X790065Y345985D03*
Y415985D03*
Y405985D03*
Y395985D03*
Y375985D03*
X800065D03*
X790065Y365985D03*
X800065D03*
Y355985D03*
X790065D03*
X790975Y621407D03*
X795975D03*
X800975D03*
X805975D03*
X810975D03*
X815975D03*
X820975D03*
X825975D03*
X830975D03*
X835975D03*
X840975D03*
X854971Y637313D03*
Y642313D03*
Y647313D03*
Y652313D03*
Y657313D03*
Y662313D03*
Y667313D03*
Y672313D03*
Y677313D03*
Y682313D03*
Y687313D03*
Y692313D03*
Y697313D03*
Y702313D03*
Y707313D03*
Y712313D03*
X916683Y62377D03*
Y57377D03*
Y52377D03*
Y47377D03*
Y42377D03*
Y37377D03*
Y32377D03*
Y27377D03*
Y22377D03*
Y17377D03*
X915546Y8514D03*
X910546D03*
X905546D03*
X900546D03*
X916683Y132377D03*
Y127377D03*
Y122377D03*
Y117377D03*
Y112377D03*
Y107377D03*
Y102377D03*
Y97377D03*
Y92377D03*
Y87377D03*
Y82377D03*
Y77377D03*
Y72377D03*
Y67377D03*
X897250Y81510D03*
X916683Y207377D03*
Y202377D03*
Y197377D03*
Y192377D03*
Y187377D03*
Y182377D03*
Y177377D03*
Y172377D03*
Y167377D03*
Y162377D03*
Y157377D03*
Y152377D03*
Y147377D03*
Y142377D03*
Y137377D03*
Y277377D03*
Y272377D03*
Y267377D03*
Y262377D03*
Y257377D03*
Y252377D03*
Y247377D03*
Y242377D03*
Y237377D03*
Y232377D03*
Y227377D03*
Y222377D03*
Y217377D03*
Y212377D03*
Y347377D03*
Y342377D03*
Y337377D03*
Y332377D03*
Y327377D03*
Y322377D03*
Y317377D03*
Y312377D03*
Y307377D03*
Y302377D03*
Y297377D03*
Y292377D03*
Y287377D03*
Y282377D03*
Y422377D03*
Y417377D03*
Y412377D03*
Y407377D03*
Y402377D03*
Y397377D03*
Y392377D03*
Y387377D03*
Y382377D03*
Y377377D03*
Y372377D03*
Y367377D03*
Y362377D03*
Y357377D03*
Y352377D03*
Y492377D03*
Y487377D03*
Y482377D03*
Y477377D03*
Y472377D03*
Y467377D03*
Y462377D03*
Y457377D03*
Y452377D03*
Y447377D03*
Y442377D03*
Y437377D03*
Y432377D03*
Y427377D03*
Y562377D03*
Y557377D03*
Y552377D03*
Y547377D03*
Y542377D03*
Y537377D03*
Y532377D03*
Y527377D03*
Y522377D03*
Y517377D03*
Y512377D03*
Y507377D03*
Y502377D03*
Y497377D03*
Y637377D03*
Y632377D03*
Y627377D03*
Y622377D03*
Y617377D03*
Y612377D03*
Y607377D03*
Y602377D03*
Y597377D03*
Y592377D03*
Y587377D03*
Y582377D03*
Y577377D03*
Y572377D03*
Y567377D03*
Y707377D03*
Y702377D03*
Y697377D03*
Y692377D03*
Y687377D03*
Y682377D03*
Y677377D03*
Y672377D03*
Y667377D03*
Y662377D03*
Y657377D03*
Y652377D03*
Y647377D03*
Y642377D03*
X901041Y753684D03*
X903277Y749212D03*
X905513Y744740D03*
X907749Y740268D03*
X909985Y735796D03*
X912221Y731323D03*
X914457Y726851D03*
X916683Y722377D03*
Y717377D03*
Y712377D03*
G54D21*
G01X323492Y214234D02*
X319272Y210014D01*
X305862D01*
G01X689875Y464586D02*
X696070Y470781D01*
Y483486D01*
G01X711300Y423800D02*
X712000Y424500D01*
Y442100D01*
G01X725200D02*
X722300Y445000D01*
X714900D01*
X712000Y442100D01*
G01X740500Y431000D02*
X735300D01*
X725200Y442100D01*
G01X794200Y422800D02*
X802486Y414514D01*
Y404714D01*
X811300Y395900D01*
G01X794900Y441100D02*
Y423500D01*
X794200Y422800D01*
G01X794900Y441100D02*
X797808Y444008D01*
X805192D01*
X808100Y441100D01*
G54D12*
G01X-36569Y-23804D02*
Y-103804D01*
G01D02*
X1258031D01*
G01X-40569Y-7804D02*
G02I-12000J0D01*
G01X-45719D02*
G02I-6850J0D01*
G01X-52569Y-23804D02*
Y8196D01*
G01X-36569Y-23804D02*
X1258031D01*
G01X-36569Y-59304D02*
X1258031D01*
G01X-36569Y-7804D02*
X-68569D01*
G01X78268Y66755D02*
X68013Y56500D01*
X38500D01*
G01X78268Y66755D02*
X94383D01*
X101550Y73922D01*
Y185760D01*
X61968Y225342D01*
Y248572D01*
X100650Y287254D01*
Y470950D01*
X98400Y473200D01*
G01X28667Y634097D02*
X20675Y626105D01*
Y461106D01*
X28123Y453658D01*
G01X86028Y696439D02*
X65589Y676000D01*
X56100D01*
G01X81549Y675547D02*
X92153D01*
X108000Y659700D01*
Y637700D01*
X105760Y635460D01*
X103940D01*
G01X138700Y636655D02*
X159945D01*
X175874Y620726D01*
Y615288D01*
X182100Y609062D01*
Y601757D01*
G01X131300Y650400D02*
Y650100D01*
G01X197243Y589900D02*
Y597243D01*
X197900Y597900D01*
Y603400D01*
X206793Y612293D01*
Y616093D01*
X210900Y620200D01*
X214000D01*
X218786Y624986D01*
Y628214D01*
X215800Y631200D01*
G01X198400Y583300D02*
Y570760D01*
X200594Y568566D01*
X204315D01*
X207149Y571400D01*
X217400D01*
X219200Y573200D01*
Y593000D01*
X235800Y609600D01*
Y615100D01*
G01X215606Y645300D02*
Y688898D01*
X206104Y698400D01*
X205800D01*
G01X200000Y664200D02*
X203100Y661100D01*
Y647500D01*
X204100Y646500D01*
G01X305682Y224074D02*
X315200Y233592D01*
Y264083D01*
X324482Y273365D01*
Y355636D01*
X323680Y356438D01*
Y378520D01*
X315878Y386322D01*
Y392698D01*
X330100Y406920D01*
Y420238D01*
X322288Y428050D01*
X308187D01*
X306937Y429300D01*
X306936D01*
X287336Y448900D01*
X280600D01*
G01X215800Y631200D02*
Y636600D01*
X217900Y638700D01*
X222322D01*
X228822Y632200D01*
X247528D01*
X250400Y635072D01*
Y636976D01*
G01X223013Y645672D02*
X221900Y646785D01*
Y669899D01*
X231795Y679794D01*
Y690200D01*
X246500Y704905D01*
Y709957D01*
X254648Y718105D01*
Y745463D01*
G01X239400Y677600D02*
Y676806D01*
X226708Y664114D01*
Y645869D01*
G01X272300Y665700D02*
X268500D01*
X263800Y670400D01*
Y677000D01*
X266050Y679250D01*
X266398D01*
G01X338301Y673907D02*
X338307Y673901D01*
X339550D01*
X351565Y661886D01*
Y650549D01*
X354240Y647874D01*
Y635508D01*
X356100Y633648D01*
Y602128D01*
X356269Y601959D01*
Y599803D01*
X355039Y598573D01*
Y595490D01*
X355700Y594829D01*
Y579317D01*
G01X290600Y668200D02*
X292869Y670469D01*
Y692062D01*
X287820Y697111D01*
Y717102D01*
X295975Y725257D01*
Y727943D01*
X288804Y735114D01*
Y736336D01*
X287220Y737920D01*
G01X470531Y-23804D02*
Y-103804D01*
G01X479040Y47134D02*
X481453Y44721D01*
X494480D01*
X496211Y42990D01*
X501691D01*
X505633Y46932D01*
G01X608031Y-23804D02*
Y-103804D01*
G01X777500Y34500D02*
X689785D01*
X685907Y30622D01*
G01X649590Y114036D02*
Y385724D01*
X698275Y434409D01*
Y438305D01*
G01X712874Y470182D02*
X710918D01*
X704900Y476200D01*
Y481717D01*
X707391Y484208D01*
G01D02*
X696792D01*
X696070Y483486D01*
G01X698275Y438305D02*
X694574Y441105D01*
X653634Y482045D01*
Y513757D01*
G01D02*
X656113Y516236D01*
X726073D01*
X739019Y529182D01*
X747082D01*
X752900Y535000D01*
X753800D01*
G01X723031Y-23804D02*
Y-103804D01*
G01X897250Y81510D02*
X883140Y67400D01*
X862600D01*
X825600Y30400D01*
X791000D01*
X782600Y22000D01*
X766200D01*
G01X723800Y18600D02*
X762800D01*
X766200Y22000D01*
G01X890531Y-23804D02*
Y-103804D01*
G01X1060531Y-23804D02*
Y-103804D01*
G01X1258031Y-23804D02*
Y-103804D01*
G01X1286031Y-7804D02*
G02I-12000J0D01*
G01X1280881D02*
G02I-6850J0D01*
G01X1274031Y-23804D02*
Y8196D01*
G01X1290031Y-7804D02*
X1258031D01*
X38500Y56500D03*
X46500Y48500D03*
X28123Y453658D03*
X53302Y567317D03*
X58926Y582407D03*
X28667Y634097D03*
X42550Y599224D03*
X56100Y676000D03*
X86268Y58755D03*
X78268Y66755D03*
X121233Y450900D03*
X98400Y473200D03*
X140490Y488605D03*
X132777Y462639D03*
X130787Y479138D03*
X113300Y448564D03*
X118065Y448535D03*
X135012Y510200D03*
X138900Y525999D03*
X81276Y548766D03*
X119605Y548705D03*
X86750Y539218D03*
X83600Y545518D03*
X89899D03*
X117200Y546300D03*
X89899Y539218D03*
X83600Y539219D03*
X86750Y545518D03*
X122600Y557480D03*
X86750Y554965D03*
Y558115D03*
X83600Y551817D03*
Y564415D03*
X86750D03*
Y551815D03*
X133800Y528500D03*
X123200Y534600D03*
X93744Y542019D03*
X96371Y534124D03*
X130607Y569636D03*
X126347Y569556D03*
X117400Y567650D03*
X74152Y567565D03*
X86750Y586463D03*
X71002Y567565D03*
X86750Y583313D03*
X74152Y580163D03*
X83601Y580164D03*
X74152Y577013D03*
X96570Y581730D03*
X138970Y632277D03*
X138700Y636655D03*
X103098Y620264D03*
X113512Y613401D03*
X113426Y609234D03*
X108137Y615870D03*
X113400Y621400D03*
Y617400D03*
X86028Y696439D03*
X131300Y650100D03*
X135000Y650000D03*
X139774Y666686D03*
X181200Y489451D03*
X155710Y485200D03*
X171537Y464400D03*
X179100Y455800D03*
X163031Y441700D03*
X193400Y463300D03*
X167680Y510640D03*
X160286Y508429D03*
X183750Y524200D03*
X143415Y530143D03*
X171200Y509840D03*
X166600Y524100D03*
X144087Y526413D03*
X176900Y496500D03*
X174717Y524010D03*
X178869Y509793D03*
X199501Y509275D03*
X156000Y496100D03*
X203696Y533000D03*
X188834Y496920D03*
X190929Y512592D03*
X150553Y512500D03*
X148050Y523740D03*
X196800Y497862D03*
X193200Y497000D03*
X174400Y519283D03*
X148409Y575672D03*
X144876Y590854D03*
X148409Y579353D03*
X144876Y587173D03*
X197611Y630698D03*
X193400Y630600D03*
X188899Y629597D03*
X185500Y629700D03*
X195600Y646000D03*
X205800Y698400D03*
X200000Y664200D03*
X204100Y646500D03*
X199600Y646300D03*
X195500Y696900D03*
X207000Y654400D03*
X185598Y709274D03*
X182200Y709400D03*
X143174Y666586D03*
X162100Y711215D03*
X275276Y494017D03*
X277455Y446150D03*
X254100Y440800D03*
X257950Y440600D03*
X226500Y477000D03*
X267670Y485870D03*
X271100Y485900D03*
X222995Y443805D03*
X240900Y440900D03*
X236400Y440800D03*
X280600Y448900D03*
X214900Y490000D03*
X276591Y483709D03*
X245874Y458478D03*
X242500Y458900D03*
X253400Y453500D03*
X273400Y449700D03*
X249465Y458000D03*
X252626Y469150D03*
X244400Y478600D03*
X244300Y474150D03*
X233664Y482859D03*
X226607Y444058D03*
X230610Y444055D03*
X233850Y552201D03*
X254494Y529198D03*
X244850Y540150D03*
X248700Y540000D03*
X228200Y496200D03*
X227100Y525400D03*
X228800Y542100D03*
X238600Y509900D03*
X228313Y552169D03*
X233100Y509800D03*
X275100D03*
X260900Y553900D03*
X242600Y509800D03*
X233607Y557671D03*
X250400Y636976D03*
X215800Y631200D03*
X274800Y607500D03*
X270300Y622315D03*
X242333Y593800D03*
X218200Y609500D03*
X235800Y615100D03*
X233447Y603747D03*
X232300Y600300D03*
X279214Y591383D03*
X275652Y577455D03*
X237100Y590000D03*
X234087Y618038D03*
X248800Y582000D03*
X273022Y580751D03*
X259000Y617000D03*
X281975Y572963D03*
X279800Y569182D03*
X261810Y633980D03*
X264800Y632300D03*
X276783Y588907D03*
X258873Y631373D03*
X215400Y626800D03*
X276400Y700650D03*
X223013Y645672D03*
X272300Y665700D03*
X266398Y679250D03*
X226708Y645869D03*
X239400Y677600D03*
X267045Y695881D03*
X215606Y645300D03*
X277600Y680200D03*
X276400Y697250D03*
X255000Y679900D03*
X254648Y745463D03*
X305682Y224074D03*
X321859Y388315D03*
X321100Y384874D03*
X295700Y428400D03*
X293326Y494174D03*
X343050Y438900D03*
X339900Y454000D03*
X328313Y435513D03*
X324916Y435360D03*
X321700Y436650D03*
X293600Y518400D03*
X288000Y561000D03*
X313300Y518800D03*
X288311Y496200D03*
X298200Y521100D03*
X301300Y524400D03*
X331900Y549700D03*
X329050Y552315D03*
X348220Y563836D03*
X344812Y563844D03*
X335000Y497000D03*
X332698Y543738D03*
X336723Y542000D03*
X327800Y514900D03*
X330200Y531800D03*
X323400Y507540D03*
X286061Y502378D03*
X293500Y522600D03*
X309600Y520150D03*
X312300Y540600D03*
X332940Y539287D03*
X333400Y503800D03*
X327417Y548344D03*
X355700Y579317D03*
X341755Y627231D03*
Y623682D03*
X352716Y594135D03*
X293500Y625600D03*
X293600Y629100D03*
X321421Y605265D03*
X303000Y586800D03*
X285400Y572556D03*
X325761Y592959D03*
X325899Y589186D03*
X355100Y651827D03*
X290600Y668200D03*
X338301Y673907D03*
X328600Y661100D03*
X343372Y655836D03*
X347013Y656090D03*
X328087Y701587D03*
X327062Y697600D03*
X332200Y643800D03*
X288720Y641455D03*
X336000Y662200D03*
X336387Y648987D03*
X338135Y670511D03*
X342542Y685983D03*
X342645Y682506D03*
X300700Y667000D03*
X287220Y737920D03*
X334000Y714640D03*
X293075Y726600D03*
X342208Y714950D03*
X337481Y719818D03*
X425765Y56265D03*
X387833Y82930D03*
X391382D03*
X399900Y152100D03*
X398000Y165400D03*
X398050Y162000D03*
X406400Y150300D03*
X386250Y318250D03*
X376910Y366078D03*
X377300Y362700D03*
X366700Y454800D03*
X359400Y451600D03*
X380200Y457800D03*
X381400Y462000D03*
X387500Y458200D03*
X370800Y475128D03*
X389081Y475224D03*
X387950Y466800D03*
X394952Y485300D03*
X370900Y471700D03*
X373700Y482700D03*
X378200Y476600D03*
X387800Y525500D03*
X387700Y521600D03*
X397650Y508250D03*
Y536671D03*
X394880Y548670D03*
X393465Y553100D03*
X387700Y517700D03*
X383126Y565162D03*
X396400Y545500D03*
X390769Y495379D03*
X393889Y543207D03*
X364300Y592900D03*
X375700Y580102D03*
X390600Y625500D03*
X380572Y592095D03*
X374200Y645871D03*
X379100Y703300D03*
X363664Y688950D03*
X384466Y661650D03*
X364600Y670800D03*
X390500Y665800D03*
Y669200D03*
X361914Y680181D03*
X401000Y676500D03*
X371457Y667593D03*
X368060Y667743D03*
X390355Y690926D03*
X373060Y702960D03*
X398600Y662700D03*
X472800Y50000D03*
X469000Y50100D03*
X479040Y47134D03*
X458041Y47341D03*
X476100Y60500D03*
X478700Y62800D03*
X462372Y49179D03*
X496355Y26000D03*
X496242Y22287D03*
X486700Y31100D03*
X448000Y80404D03*
X444800Y82404D03*
X478590Y70310D03*
X482200Y70500D03*
X455766Y114535D03*
X457000Y117800D03*
X480538Y112071D03*
X441100Y110950D03*
X448996Y117666D03*
X515700Y50899D03*
X515785Y55552D03*
X505633Y46932D03*
X502300Y58200D03*
X531050Y46998D03*
X528300Y58648D03*
X515500Y59000D03*
X532500Y58600D03*
X543059Y108958D03*
X540800Y111500D03*
X582797Y31807D03*
X588753Y24080D03*
X642998Y127863D03*
X642574Y131843D03*
X685907Y30622D03*
X680300Y17500D03*
X696070Y483486D03*
X712874Y470182D03*
X707391Y484208D03*
X712000Y442100D03*
X711300Y423800D03*
X669749Y458022D03*
X653634Y513757D03*
X777500Y34500D03*
X766200Y22000D03*
X723800Y18600D03*
X725288Y405950D03*
X725200Y442100D03*
X740500Y431000D03*
X759342Y543603D03*
X842022Y152174D03*
X848868Y219064D03*
X794200Y422800D03*
X811300Y395900D03*
X849420Y407748D03*
X822300Y390000D03*
X794900Y441100D03*
X808100D03*
G54D22*
G01X130607Y569636D02*
G03X128977Y568006I0J-1630D01*
G01Y567721D01*
G02X127267Y566011I-1710J0D01*
G01X124344D01*
G02X121800Y568555I0J2544D01*
G01Y569027D01*
G03X120259Y570600I-1573J0D01*
G01X117070D01*
G03X115656Y570014I0J-1999D01*
G01X114033Y568391D01*
G02X112619Y567805I-1414J1413D01*
G01X108934D01*
G03X107520Y567219I0J-1999D01*
G01X99681Y559380D01*
G02X98267Y558794I-1414J1413D01*
G01X94044D01*
G03X93032Y558375I0J-1431D01*
G03X92756Y557612I914J-762D01*
G01Y557077D01*
G02X92174Y555672I-1987J0D01*
G02X90770Y555090I-1405J1405D01*
G01X88859D01*
X88009Y555940D01*
X87725D01*
X86750Y554965D01*
G01X126347Y569556D02*
G02X127777Y568126I0J-1430D01*
G01Y567721D01*
G02X127267Y567211I-510J0D01*
G01X124344D01*
G02X123000Y568555I0J1344D01*
G01Y569027D01*
G03X120283Y571800I-2774J0D01*
G01X117070D01*
G03X114807Y570863I-1J-3199D01*
G01X113184Y569240D01*
G02X112619Y569005I-566J564D01*
G01X108934D01*
G03X106671Y568068I-1J-3199D01*
G01X98832Y560229D01*
G02X98267Y559994I-566J564D01*
G01X94044D01*
G03X92146Y559186I-1J-2631D01*
G03X91556Y557612I1800J-1572D01*
G01Y557077D01*
G02X91325Y556521I-787J1D01*
G02X90769Y556290I-557J556D01*
G01X89357D01*
X88507Y557140D01*
X87725D01*
X86750Y558115D01*
G01X148409Y575672D02*
G03X146542Y577006I-1867J-639D01*
G01X138204D01*
G02X134173Y578675I-1J5700D01*
G01X132940Y579908D01*
G03X130906Y580750I-2033J-2033D01*
G01X106694D01*
G03X105161Y580115I0J-2168D01*
G01X97193Y572147D01*
X96235Y571190D01*
G02X93776Y570171I-2460J2460D01*
G01X93061D01*
G03X92271Y569776I1J-990D01*
G02X91481Y569381I-791J595D01*
G01X90281D01*
G02X89491Y569776I1J990D01*
G03X88701Y570171I-791J-595D01*
G01X87501D01*
G03X86711Y569776I1J-990D01*
G02X85921Y569381I-791J595D01*
G01X84721D01*
G02X83931Y569776I1J990D01*
G03X83141Y570171I-791J-595D01*
G01X82580D01*
G03X81936Y569527I0J-644D01*
G01Y562222D01*
G02X76818I-2559J0D01*
G01Y572749D01*
G03X76437Y573669I-1302J0D01*
G01Y573668D01*
G03X75518Y574048I-919J-921D01*
G01X74737D01*
G03X73404Y573496I0J-1886D01*
G01X73355Y573447D01*
G03X72754Y571996I1451J-1451D01*
G01Y568569D01*
G03X73758Y567565I1004J0D01*
G01X74152D01*
G01X71002D02*
G03X71554Y568898I-1333J1333D01*
G01Y571996D01*
G02X72506Y574296I3252J1D01*
G01X72555Y574345D01*
G02X74737Y575248I2181J-2183D01*
G01X75518D01*
G02X77286Y574518I2J-2502D01*
G02X78018Y572748I-1770J-1768D01*
G01Y562222D01*
G03X80736I1359J0D01*
G01Y569527D01*
G02X82580Y571371I1844J0D01*
G01X93775D01*
G03X95386Y572039I-1J2279D01*
G01X104312Y580964D01*
G02X106693Y581950I2381J-2382D01*
G01X130906D01*
G02X133789Y580757I2J-4075D01*
G01X135022Y579524D01*
G03X138204Y578206I3182J3182D01*
G01X146542D01*
G03X148409Y579353I0J2093D01*
G01X86750Y586463D02*
X87490Y585723D01*
G03X88410Y585342I920J920D01*
G01X93871D01*
G03Y589401I0J2030D01*
G01X84327D01*
G02Y595186I0J2893D01*
G01X98948D01*
G02X101455Y593678I1J-2836D01*
G01X101454Y593677D01*
G02X101562Y593387I-1054J-557D01*
G03X103183Y592099I1621J376D01*
G03X104376Y592917I0J1279D01*
G03X104391Y592950I-460J229D01*
G01X104390D01*
G02X109696Y593215I2717J-1145D01*
G02X109769Y593056I-1126J-613D01*
G03X111186Y592132I1417J625D01*
G03X112628Y593237I0J1493D01*
G01X112629D01*
G02X115248Y595186I2544J-684D01*
G01X117291D01*
G03X119054Y595906I-1J2520D01*
G01X120289Y597141D01*
G02X124127Y598730I3838J-3841D01*
G01X138717D01*
G02X141290Y596157I0J-2573D01*
G01Y591123D01*
G03X142800Y589613I1510J0D01*
G01X143469D01*
G03X144876Y590854I0J1418D01*
G01Y587173D02*
G03X143470Y588413I-1406J-177D01*
G01X142800D01*
G02X140090Y591123I0J2710D01*
G01Y596157D01*
G03X138717Y597530I-1373J0D01*
G01X124128D01*
G03X121138Y596292I0J-4230D01*
G01X119899Y595053D01*
G02X117291Y593986I-2608J2654D01*
G01X115214D01*
G03X113788Y592925I-41J-1433D01*
G02X111186Y590932I-2602J702D01*
G02X108642Y592641I0J2748D01*
G03X105496Y592484I-1535J-836D01*
G02X103183Y590899I-2313J895D01*
G02X100393Y593116I0J2864D01*
G03X98948Y593986I-1445J-765D01*
G01X84327D01*
G03Y590601I0J-1692D01*
G01X93871D01*
G02Y584142I0J-3229D01*
G01X88410D01*
G03X86992Y583554I1J-2006D01*
G01X86750Y583313D01*
G54D13*
X168898Y548819D03*
X159449Y561417D03*
X172047D03*
X168898Y558268D03*
X159449Y555118D03*
X184645Y542519D03*
X159449Y542521D03*
X165749Y548819D03*
X181496Y542520D03*
X159449Y548821D03*
X172047Y548819D03*
X168898Y551969D03*
X162599Y548821D03*
X168898Y555119D03*
X181497Y548821D03*
X178346Y545670D03*
X181497Y545671D03*
X203542Y551970D03*
X159412Y552006D03*
X165748Y551968D03*
X209842Y545669D03*
X212992Y551969D03*
Y548819D03*
X209842Y551969D03*
X206692Y548820D03*
X206693Y551969D03*
X194094Y545669D03*
Y548820D03*
X153150Y539371D03*
X153149Y542521D03*
X197244Y545669D03*
Y542519D03*
X156300Y539371D03*
X197243Y589900D03*
X194093Y596063D03*
X175196Y589764D03*
X172048D03*
X168898D03*
X206692Y592913D03*
X165748Y583464D03*
X212992Y586614D03*
X159449D03*
X162598Y580315D03*
X165748Y586614D03*
X156299Y577165D03*
X159449Y580315D03*
X162598Y583464D03*
X165748Y567717D03*
X190945Y599213D03*
X190944Y596063D03*
X203543Y602362D03*
X194093Y592913D03*
X190944D03*
X200393Y586614D03*
X197165Y586540D03*
X181500Y595900D03*
X200393Y592912D03*
X159448Y592913D03*
X162598Y589764D03*
X165748D03*
Y596063D03*
Y592913D03*
X175197D03*
X172048D03*
X219291Y542519D03*
X216141D03*
Y551970D03*
X230600Y608100D03*
G54D23*
G01X118065Y448535D02*
X103400Y433870D01*
Y286114D01*
X64718Y247432D01*
Y226482D01*
X104300Y186900D01*
Y72782D01*
X92518Y61000D01*
X78251D01*
X65751Y48500D01*
X46500D01*
G01X86268Y58755D02*
X92395D01*
X105800Y72160D01*
Y187522D01*
X66218Y227104D01*
Y246810D01*
X104900Y285492D01*
Y432675D01*
X121233Y449008D01*
Y450900D01*
G01X42550Y599224D02*
X63590Y620264D01*
X103098D01*
G01X132777Y462639D02*
X131855Y463561D01*
Y468184D01*
X147200Y483529D01*
Y487783D01*
X147150Y487833D01*
Y489367D01*
X147200Y489417D01*
Y494322D01*
X148775Y495897D01*
Y506525D01*
X143830Y511470D01*
Y521138D01*
X142437Y522531D01*
Y527963D01*
X139148Y531252D01*
X136012D01*
X132864Y534400D01*
X123400D01*
X123200Y534600D01*
G01X130787Y479138D02*
X120005Y468356D01*
Y455269D01*
X113300Y448564D01*
G01X159449Y561417D02*
X154600D01*
X150600Y557417D01*
X136890D01*
X136390Y557917D01*
Y558917D01*
X136890Y559417D01*
X148890D01*
X149390Y559917D01*
Y560917D01*
X148890Y561417D01*
X117944D01*
X116884Y560357D01*
X112749D01*
X105737Y553345D01*
X103389D01*
X101131Y551087D01*
X96439D01*
X94995Y549643D01*
X82153D01*
X81276Y548766D01*
G01X91461Y540793D02*
X91885Y540369D01*
X95518D01*
X96166Y541017D01*
X108235D01*
X116084Y548866D01*
X119444D01*
X119605Y548705D01*
G01X172047Y561417D02*
X170497Y562967D01*
X161955D01*
X161048Y562060D01*
Y560823D01*
X160042Y559817D01*
X154710D01*
X153920Y559027D01*
Y556740D01*
X151510Y554330D01*
X134890D01*
X134390Y554830D01*
Y558860D01*
X133833Y559417D01*
X132168D01*
X131668Y558917D01*
Y554960D01*
X131168Y554460D01*
X130168D01*
X129668Y554960D01*
Y558917D01*
X129168Y559417D01*
X128168D01*
X127668Y558917D01*
Y557050D01*
X127168Y556550D01*
X126168D01*
X125668Y557050D01*
Y558917D01*
X125168Y559417D01*
X118773D01*
X117713Y558357D01*
X113578D01*
X106566Y551345D01*
X104218D01*
X101890Y549017D01*
X96166D01*
X95892Y548743D01*
X86825D01*
X83600Y545518D01*
G01X89899D02*
X90874Y544543D01*
X95812D01*
X96286Y545017D01*
X106577D01*
X114920Y553360D01*
X124445D01*
X125570Y552235D01*
X127254D01*
X127754Y551735D01*
Y550180D01*
X128254Y549680D01*
X129254D01*
X129754Y550180D01*
Y551735D01*
X130254Y552235D01*
X131254D01*
X131754Y551735D01*
Y550180D01*
X132254Y549680D01*
X133254D01*
X133754Y550180D01*
Y551735D01*
X134254Y552235D01*
X135254D01*
X135754Y551735D01*
Y549480D01*
X136254Y548980D01*
X137254D01*
X137754Y549480D01*
Y551735D01*
X138254Y552235D01*
X139254D01*
X139754Y551735D01*
Y548980D01*
X140254Y548480D01*
X141254D01*
X141754Y548980D01*
Y551735D01*
X142254Y552235D01*
X143254D01*
X143754Y551735D01*
Y548780D01*
X144254Y548280D01*
X145254D01*
X145754Y548780D01*
Y551735D01*
X146254Y552235D01*
X152464D01*
X158462Y558233D01*
X160262D01*
X161847Y559818D01*
X167348D01*
X168898Y558268D01*
G01X117200Y546300D02*
X109917Y539017D01*
X90100D01*
X89899Y539218D01*
G01X159449Y555118D02*
X159148D01*
X144280Y540250D01*
X130533D01*
X127300Y537017D01*
X125024D01*
X124524Y537517D01*
Y540050D01*
X124024Y540550D01*
X123024D01*
X122524Y540050D01*
Y536910D01*
X122024Y536410D01*
X121024D01*
X120524Y536910D01*
Y542310D01*
X120024Y542810D01*
X119024D01*
X118524Y542310D01*
Y534820D01*
X118024Y534320D01*
X117024D01*
X116524Y534820D01*
Y540790D01*
X116024Y541290D01*
X115024D01*
X114524Y540790D01*
Y537517D01*
X114024Y537017D01*
X93540D01*
X93284Y537273D01*
X85546D01*
X83600Y539219D01*
G01X107395Y549345D02*
X105047D01*
X102719Y547017D01*
X96731D01*
X95157Y545443D01*
X92308D01*
X90583Y547168D01*
X88400D01*
X86750Y545518D01*
G01X117400Y567650D02*
X114107Y564357D01*
X108449D01*
X99936Y555844D01*
X96166D01*
X95830Y555508D01*
X93428D01*
X91687Y553767D01*
G01X91287Y562855D02*
X96905D01*
X106005Y571955D01*
X111646D01*
X114491Y574800D01*
X128860D01*
X133475Y570185D01*
Y567393D01*
X134268Y566600D01*
X139430D01*
X139930Y567100D01*
Y567636D01*
X142294Y570000D01*
X151680D01*
X152364Y569316D01*
X166846D01*
X167348Y569818D01*
Y577742D01*
X166360Y578730D01*
X159206D01*
G03X158035Y578245I0J-1656D01*
G01X157405Y577615D01*
G02X156319Y577165I-1086J1086D01*
G01X156299D01*
G01X159449Y580315D02*
G03X158026Y579725I1J-2013D01*
G01X157545Y579245D01*
X157036Y578736D01*
X151940D01*
X151440Y578236D01*
Y575940D01*
X151940Y575440D01*
X163460D01*
X163960Y574940D01*
Y572940D01*
X163460Y572440D01*
X154330D01*
X153330Y571440D01*
X143290D01*
X142660Y572070D01*
Y573193D01*
X141860Y573993D01*
X140114D01*
X139314Y573193D01*
Y571317D01*
X138814Y570817D01*
X136814D01*
X136314Y571317D01*
Y572362D01*
X130876Y577800D01*
X113248D01*
X110403Y574955D01*
X104731D01*
X95753Y565977D01*
X92377D01*
G01X165748Y567717D02*
X164198Y566167D01*
X156943D01*
X155580Y567530D01*
X143080D01*
X142580Y567030D01*
Y566030D01*
X143080Y565530D01*
X153940D01*
X154440Y565030D01*
Y564030D01*
X153940Y563530D01*
X117228D01*
X116055Y562357D01*
X109278D01*
X107558Y560637D01*
Y559929D01*
X108135Y559352D01*
Y558644D01*
X107428Y557937D01*
X106720D01*
X106143Y558514D01*
X105435D01*
X100765Y553844D01*
X96166D01*
X96007Y554003D01*
X93893D01*
X91705Y551815D01*
X86750D01*
G01X140490Y488605D02*
Y496776D01*
X135989Y501277D01*
X118173D01*
X116817Y502633D01*
Y526208D01*
X118621Y528012D01*
X133312D01*
X133800Y528500D01*
G01X93744Y542019D02*
X95168D01*
X96166Y543017D01*
X107406D01*
X115749Y551360D01*
X121900D01*
X122400Y550860D01*
Y543280D01*
X123130Y542550D01*
X124853D01*
X126493Y540910D01*
X128364D01*
X129704Y542250D01*
X130906D01*
X131406Y542750D01*
Y544880D01*
X131906Y545380D01*
X132906D01*
X133406Y544880D01*
Y542750D01*
X133906Y542250D01*
X134906D01*
X135406Y542750D01*
Y545830D01*
X135906Y546330D01*
X136906D01*
X137406Y545830D01*
Y542750D01*
X137906Y542250D01*
X138906D01*
X139406Y542750D01*
Y545960D01*
X139906Y546460D01*
X140906D01*
X141406Y545960D01*
Y542750D01*
X141906Y542250D01*
X144078D01*
X158496Y556668D01*
X167349D01*
X168898Y555119D01*
G01X74152Y580163D02*
X73497D01*
X70720Y582940D01*
Y596048D01*
X77822Y603150D01*
X115425D01*
X117045Y604770D01*
X143614D01*
X149424Y598960D01*
X150370D01*
X153110Y596220D01*
Y594330D01*
X157590Y589850D01*
Y588473D01*
X159449Y586614D01*
G01X83601Y580164D02*
Y578720D01*
X82801Y577920D01*
X79736D01*
X78936Y578720D01*
Y587091D01*
X79736Y587891D01*
X82221D01*
X83021Y587091D01*
Y584549D01*
X86279Y581291D01*
X87878D01*
X88401Y581814D01*
X93986D01*
X96456Y579344D01*
X98444D01*
X104000Y584900D01*
X130202D01*
X130702Y585400D01*
Y588410D01*
X131202Y588910D01*
X133202D01*
X133702Y588410D01*
Y585400D01*
X134202Y584900D01*
X135774D01*
X138896Y581778D01*
X140468D01*
X141062Y581184D01*
X146434D01*
X147650Y582400D01*
X150600D01*
X151434Y581566D01*
X155195D01*
G02X156161Y581966I966J-966D01*
G01X160195D01*
G02X161478Y581434I-1J-1815D01*
G01X162598Y580315D01*
G01X74152Y577013D02*
Y577442D01*
X76040Y579330D01*
Y592291D01*
X82969Y599220D01*
X117240D01*
X119700Y601680D01*
X142028D01*
X148008Y595700D01*
X149580D01*
X153450Y591830D01*
Y587000D01*
X155910Y584540D01*
X160000D01*
X160526Y585066D01*
X162114D01*
G02X162995Y584966I0J-3931D01*
G03X165748Y586614I519J2257D01*
G01X96570Y581730D02*
X102740Y587900D01*
X127160D01*
X127660Y588400D01*
Y590400D01*
X127160Y590900D01*
X122970D01*
X122470Y591400D01*
Y593400D01*
X122970Y593900D01*
X135140D01*
X136800Y592240D01*
Y588659D01*
X140616Y584843D01*
X142532D01*
X143407Y583968D01*
X147108D01*
X147566Y584426D01*
Y593120D01*
X148066Y593620D01*
X150066D01*
X150566Y593120D01*
Y584344D01*
X151944Y582966D01*
X162100D01*
X162598Y583464D01*
G01X138970Y632277D02*
X139721Y633028D01*
X155272D01*
X179897Y608403D01*
Y598604D01*
X181051Y597450D01*
X182351D01*
X186245Y593556D01*
Y592271D01*
X187152Y591364D01*
X188037D01*
X188038Y591363D01*
X191587D01*
X193137Y592913D01*
X194093D01*
G01X113512Y613401D02*
X122721D01*
X124572Y611550D01*
X130286D01*
X133425Y614689D01*
X142745D01*
X150984Y606450D01*
Y603050D01*
X157898Y596136D01*
Y595420D01*
X159448Y593870D01*
Y592913D01*
G01X113426Y609234D02*
X116093Y611901D01*
X122099D01*
X123950Y610050D01*
X130908D01*
X134047Y613189D01*
X142501D01*
X150084Y605606D01*
Y602677D01*
X156998Y595763D01*
Y593170D01*
X158805Y591363D01*
X160137D01*
X161736Y589764D01*
X162598D01*
G01X165748D02*
X164791D01*
X163241Y591314D01*
X162004D01*
X161000Y592318D01*
Y596704D01*
X160041Y597663D01*
X158805D01*
X157898Y598570D01*
Y602957D01*
X152714Y608141D01*
X150566D01*
X148753Y609954D01*
Y611484D01*
X144048Y616189D01*
X131911D01*
X128800Y619300D01*
X123728D01*
X119679Y615251D01*
X108756D01*
X108137Y615870D01*
G01X113400Y621400D02*
X116600D01*
X120400Y625200D01*
X138540D01*
X142520Y621220D01*
X150680D01*
X154200Y617700D01*
Y611507D01*
X164148Y601559D01*
Y598352D01*
X165748Y596752D01*
Y596063D01*
G01X113400Y617400D02*
X118999D01*
X124799Y623200D01*
X137711D01*
X142722Y618189D01*
X144877D01*
X151116Y611950D01*
X152484D01*
X161048Y603386D01*
Y598570D01*
X162005Y597613D01*
X163241D01*
X164151Y596703D01*
Y594510D01*
X165748Y592913D01*
G01X143174Y666586D02*
X142863Y666275D01*
Y646902D01*
X136850Y640889D01*
Y631780D01*
X138296Y630334D01*
X142544D01*
X145205Y627673D01*
X155797D01*
X176747Y606723D01*
Y594463D01*
X175197Y592913D01*
G01X139774Y666686D02*
X140237Y666223D01*
Y647812D01*
X134349Y641924D01*
Y639854D01*
X134350Y639853D01*
Y630744D01*
X137260Y627834D01*
X141328D01*
X143989Y625173D01*
X154761D01*
X173598Y606336D01*
Y594463D01*
X172048Y592913D01*
G01X181200Y489451D02*
X182900Y491151D01*
Y501800D01*
X184814Y503714D01*
Y511414D01*
X185600Y512200D01*
Y528000D01*
X183095Y530505D01*
Y540969D01*
X184645Y542519D01*
G01X155710Y485200D02*
X152700Y488210D01*
Y514000D01*
X159449Y520749D01*
Y542521D01*
G01X171537Y464400D02*
X174750Y467613D01*
Y497150D01*
X173050Y498850D01*
Y504650D01*
X176868Y508468D01*
Y510621D01*
X177099Y510852D01*
Y525744D01*
X177500Y526145D01*
Y542227D01*
X179896Y544623D01*
Y547220D01*
X181497Y548821D01*
G01X222995Y443805D02*
X184602D01*
X176900Y451507D01*
Y459336D01*
X177600Y460036D01*
Y467730D01*
X176900Y468430D01*
Y496500D01*
G01X179100Y455800D02*
Y496100D01*
X180850Y497850D01*
Y507812D01*
X178869Y509793D01*
G01X163031Y441700D02*
Y451147D01*
X160687Y453491D01*
Y491413D01*
X156000Y496100D01*
G01X193400Y463300D02*
X204392Y474292D01*
Y493824D01*
X205361Y494793D01*
Y508279D01*
X206850Y509768D01*
Y524150D01*
X205440Y525560D01*
Y531060D01*
X203696Y532804D01*
Y533000D01*
G01X226607Y444058D02*
X218407Y452258D01*
X215805D01*
X206520Y461543D01*
Y493830D01*
X209350Y496660D01*
Y510980D01*
X208729Y511601D01*
Y525514D01*
X206700Y527543D01*
Y540320D01*
X205142Y541878D01*
Y547270D01*
X206692Y548820D01*
G01X167680Y510640D02*
Y521680D01*
X168450Y522450D01*
Y539878D01*
X170448Y541876D01*
Y547269D01*
X168898Y548819D01*
G01X160286Y508429D02*
X160700Y508843D01*
Y509900D01*
X162747Y511947D01*
Y523869D01*
X161049Y525567D01*
Y543162D01*
X161956Y544069D01*
X161969D01*
X162019Y544119D01*
X163242D01*
X164199Y545076D01*
Y546312D01*
X165749Y547862D01*
Y548819D01*
G01X183750Y524200D02*
X183000Y524950D01*
Y528000D01*
X181699Y529301D01*
Y530511D01*
X180700Y531510D01*
Y541724D01*
X181496Y542520D01*
G01X143415Y530143D02*
Y537016D01*
X155220Y548821D01*
X159449D01*
G01X171200Y509840D02*
X172700Y511340D01*
Y516000D01*
X170515Y518185D01*
Y526035D01*
X173597Y529117D01*
Y547269D01*
X172047Y548819D01*
G01X168898Y551969D02*
Y550998D01*
X168269Y550369D01*
X168255D01*
X167348Y549462D01*
Y545075D01*
X166378Y544105D01*
X165134D01*
X164227Y543198D01*
Y543190D01*
X164199Y543162D01*
Y526501D01*
X166600Y524100D01*
G01X144087Y526413D02*
X145500Y527826D01*
Y537610D01*
X155111Y547221D01*
X160621D01*
X162221Y548821D01*
X162599D01*
G01X174717Y524010D02*
Y526191D01*
X176154Y527628D01*
Y542154D01*
X177800Y543800D01*
Y545124D01*
X178346Y545670D01*
G01X178869Y509793D02*
X180200Y511124D01*
Y515500D01*
X181500Y516800D01*
Y528227D01*
X180799Y528928D01*
Y530138D01*
X178900Y532037D01*
Y542117D01*
X181497Y544714D01*
Y545671D01*
G01X199501Y509275D02*
X199600D01*
X199925Y509600D01*
X202217D01*
X205350Y512733D01*
Y520450D01*
X201960Y523840D01*
Y550388D01*
X203542Y551970D01*
G01X214900Y490000D02*
X213550Y491350D01*
Y516423D01*
X210500Y519473D01*
Y533874D01*
X209842Y534532D01*
Y545669D01*
G01Y551969D02*
X210799D01*
X212349Y550419D01*
X219885D01*
X220850Y549454D01*
Y524082D01*
X226743Y518189D01*
X229450D01*
X236450Y511189D01*
Y506867D01*
X233664Y504081D01*
Y482859D01*
G01X230610Y444055D02*
X229100Y445565D01*
Y451264D01*
X220607Y459757D01*
Y474393D01*
X216800Y478200D01*
Y517200D01*
X214000Y520000D01*
Y532800D01*
X211441Y535359D01*
Y549413D01*
X210435Y550419D01*
X209199D01*
X207649Y551969D01*
X206693D01*
G01X188834Y496920D02*
X188600Y497154D01*
Y501000D01*
X189000Y501400D01*
Y522583D01*
X189350Y522933D01*
Y524467D01*
X189000Y524817D01*
Y526400D01*
X190800Y528200D01*
Y536700D01*
X192544Y538444D01*
Y544119D01*
X194094Y545669D01*
G01X190929Y512592D02*
Y519612D01*
X193050Y521733D01*
Y536050D01*
X195644Y538644D01*
Y547270D01*
X194094Y548820D01*
G01X150553Y512500D02*
Y516097D01*
X151600Y517144D01*
Y527500D01*
X148500Y530600D01*
Y534721D01*
X153150Y539371D01*
G01X148050Y523740D02*
X147000Y524790D01*
Y536500D01*
X153021Y542521D01*
X153149D01*
G01X197244Y545669D02*
Y545256D01*
X200400Y542100D01*
Y533900D01*
X197900Y531400D01*
Y521000D01*
X200550Y518350D01*
Y512733D01*
X199467Y511650D01*
X198450D01*
X196100Y509300D01*
Y498562D01*
X196800Y497862D01*
G01X193200Y497000D02*
Y508185D01*
X193248Y508233D01*
Y509767D01*
X193200Y509815D01*
Y517800D01*
X195700Y520300D01*
Y531600D01*
X199000Y534900D01*
Y540763D01*
X197244Y542519D01*
G01X174400Y519283D02*
X172515Y521168D01*
Y526015D01*
X175200Y528700D01*
Y543200D01*
X176747Y544747D01*
Y552613D01*
X175840Y553520D01*
X168256D01*
X167348Y552612D01*
Y551375D01*
X166391Y550418D01*
X165155D01*
X164199Y549462D01*
Y548176D01*
X163242Y547219D01*
X161956D01*
X161049Y546312D01*
Y545078D01*
X160092Y544121D01*
X158856D01*
X157899Y543164D01*
Y541928D01*
X156300Y540329D01*
Y539371D01*
G01X208251Y591354D02*
X206692Y592913D01*
G01X211426Y588180D02*
X212992Y586614D01*
G01X167791Y581867D02*
X170004D01*
G01X170005Y585061D02*
X168316D01*
G01X167301Y587721D02*
Y586032D01*
G01X208251Y591354D02*
X210675D01*
X211426Y590603D01*
Y588180D01*
G01D02*
X209146D01*
X208251Y589075D01*
Y591354D01*
G01X197611Y630698D02*
X197900Y630409D01*
Y629700D01*
X195500Y627300D01*
Y616200D01*
X192500Y613200D01*
Y600900D01*
X190945Y599345D01*
Y599213D01*
G01X193400Y630600D02*
X193900Y630100D01*
Y629410D01*
X193300Y628810D01*
Y616600D01*
X189394Y612694D01*
Y597613D01*
X190944Y596063D01*
G01X203543Y602362D02*
X210681Y609500D01*
X218200D01*
G01X230600Y608100D02*
X220113Y597613D01*
X206049D01*
X205092Y596656D01*
Y589121D01*
X204185Y588214D01*
X186486D01*
X184400Y590300D01*
Y594128D01*
X182628Y595900D01*
X181500D01*
G01X200393Y592912D02*
X201992Y594511D01*
Y597211D01*
X209181Y604400D01*
X218000D01*
X228000Y614400D01*
Y620000D01*
X230000Y622000D01*
X242000D01*
X253200Y633200D01*
X257046D01*
X258873Y631373D01*
G01X215400Y626800D02*
X206350Y635850D01*
Y648250D01*
X207600Y649500D01*
Y653800D01*
X207000Y654400D01*
G01X185598Y709274D02*
Y683331D01*
X189400Y679529D01*
Y644500D01*
X191500Y642400D01*
Y634100D01*
X188899Y631499D01*
Y629597D01*
G01X182200Y709400D02*
Y683900D01*
X187400Y678700D01*
Y634500D01*
X185500Y632600D01*
Y629700D01*
G01X254100Y440800D02*
Y451371D01*
X255572Y452843D01*
Y463976D01*
X254100Y465448D01*
Y467795D01*
X254626Y468321D01*
Y472740D01*
X255359Y473473D01*
Y501843D01*
X256600Y503084D01*
Y521197D01*
X248490Y529307D01*
Y536510D01*
X244850Y540150D01*
G01X257950Y440600D02*
Y473711D01*
X257359Y474302D01*
Y501014D01*
X258600Y502255D01*
Y522026D01*
X250490Y530136D01*
Y537339D01*
X250200Y537629D01*
Y537630D01*
X248700Y539130D01*
Y540000D01*
G01X228200Y496200D02*
X224625Y492625D01*
Y478875D01*
X226500Y477000D01*
G01X321859Y388315D02*
Y393459D01*
X335450Y407050D01*
Y418778D01*
X323428Y430800D01*
X309327D01*
X308027Y432100D01*
X308026D01*
X287826Y452300D01*
X278483D01*
X269665Y461118D01*
Y474727D01*
X266359Y478033D01*
Y484559D01*
X267670Y485870D01*
G01X321100Y384874D02*
X324213Y387987D01*
Y392984D01*
X337450Y406221D01*
Y419607D01*
X324257Y432800D01*
X310156D01*
X287530Y455426D01*
Y455518D01*
X283500Y459548D01*
Y470972D01*
X271100Y483372D01*
Y485900D01*
G01X240900Y440900D02*
X240800Y441000D01*
Y446159D01*
X229550Y457409D01*
Y492950D01*
X230200Y493600D01*
Y503084D01*
X234950Y507834D01*
Y510567D01*
X233867Y511650D01*
X231160D01*
X219291Y523519D01*
Y542519D01*
G01X236400Y440800D02*
Y448437D01*
X228050Y456787D01*
Y457967D01*
X223125Y462892D01*
Y493247D01*
X223810Y493932D01*
Y513973D01*
X216141Y521642D01*
Y542519D01*
G01X275652Y577455D02*
X275667D01*
X274056Y575844D01*
Y536185D01*
X273001Y535130D01*
Y490382D01*
X276600Y486783D01*
Y483718D01*
X276591Y483709D01*
G01X245874Y458478D02*
Y461591D01*
X242400Y465065D01*
Y505858D01*
X244600Y508058D01*
Y513648D01*
X231984Y526264D01*
Y547384D01*
X237257Y552657D01*
Y589843D01*
X237100Y590000D01*
G01X242500Y458900D02*
X240400Y461000D01*
Y466600D01*
X236053Y470947D01*
Y498611D01*
X239471Y502029D01*
Y505871D01*
X240600Y507000D01*
Y511990D01*
X229790Y522800D01*
X227083D01*
X225250Y524633D01*
Y528650D01*
X226350Y529750D01*
Y547872D01*
X229963Y551485D01*
Y552853D01*
X229250Y553566D01*
Y587900D01*
X237450Y596100D01*
Y615784D01*
X235196Y618038D01*
X234087D01*
G01X253400Y453500D02*
X253572Y453672D01*
Y463147D01*
X250626Y466093D01*
Y502768D01*
X252600Y504742D01*
Y516964D01*
X239304Y530260D01*
Y536784D01*
X240949Y538429D01*
Y541695D01*
X244004Y544750D01*
X244296D01*
X246550Y547004D01*
Y551328D01*
X245996Y551882D01*
Y579196D01*
X248800Y582000D01*
G01X273400Y449700D02*
X271987D01*
X267665Y454022D01*
Y473898D01*
X264359Y477204D01*
Y498113D01*
X267250Y501004D01*
Y511667D01*
X267950Y512367D01*
Y555009D01*
X267865Y555094D01*
Y558286D01*
X270056Y560477D01*
Y577785D01*
X273022Y580751D01*
G01X249465Y458000D02*
Y462353D01*
X248626Y463192D01*
Y503597D01*
X250600Y505571D01*
Y516135D01*
X237304Y529431D01*
Y537663D01*
X238498Y538857D01*
Y542073D01*
X243175Y546750D01*
X243467D01*
X244550Y547833D01*
Y549367D01*
X243550Y550367D01*
Y583350D01*
X248650Y588450D01*
Y606650D01*
X259000Y617000D01*
G01X255000Y679900D02*
X259335Y675565D01*
Y643368D01*
X267200Y635503D01*
Y631142D01*
X260860Y624802D01*
Y606902D01*
X262960Y604802D01*
Y595692D01*
X260529Y593261D01*
X254151D01*
X250800Y589910D01*
Y580373D01*
X247996Y577569D01*
Y552711D01*
X248550Y552157D01*
Y545594D01*
X245706Y542750D01*
X244833D01*
X242965Y540882D01*
Y537497D01*
X243480Y536982D01*
Y531488D01*
X254600Y520368D01*
Y503913D01*
X252626Y501939D01*
Y469150D01*
G01X328313Y435513D02*
Y435814D01*
X317390Y446737D01*
X304798D01*
X289601Y461934D01*
Y482300D01*
X283450Y488451D01*
Y534829D01*
X281556Y536723D01*
Y560214D01*
X281975Y560633D01*
Y572963D01*
G01X279800Y569182D02*
X279556Y568938D01*
Y535894D01*
X281450Y534000D01*
Y487622D01*
X287601Y481471D01*
Y461105D01*
X303969Y444737D01*
X316561D01*
X324916Y436382D01*
Y435360D01*
G01X244400Y478600D02*
Y505029D01*
X246600Y507229D01*
Y514477D01*
X232884Y528193D01*
Y545442D01*
X239400Y551958D01*
Y587646D01*
X244183Y592429D01*
Y595388D01*
X242550Y597021D01*
Y612112D01*
X256671Y626233D01*
Y626271D01*
X261810Y631410D01*
Y633980D01*
G01X264800Y632300D02*
Y631571D01*
X258671Y625442D01*
Y625404D01*
X244550Y611283D01*
Y597850D01*
X246183Y596217D01*
Y591600D01*
X241400Y586817D01*
Y551129D01*
X236498Y546227D01*
Y539686D01*
X235304Y538492D01*
Y528602D01*
X248600Y515306D01*
Y506400D01*
X246400Y504200D01*
Y476250D01*
X244300Y474150D01*
G01X321700Y436650D02*
X319150D01*
X317600Y435100D01*
X310777D01*
X285500Y460377D01*
Y471801D01*
X273500Y483801D01*
Y487054D01*
X271000Y489554D01*
Y534900D01*
X269950Y535950D01*
Y541894D01*
X272056Y544000D01*
Y553732D01*
X269865Y555923D01*
Y557457D01*
X272056Y559648D01*
Y576673D01*
X275217Y579834D01*
Y587341D01*
X276783Y588907D01*
G01X276400Y700650D02*
X290119Y686931D01*
Y671609D01*
X285370Y666860D01*
Y627608D01*
X290050Y622928D01*
Y583831D01*
X279974Y573755D01*
Y572803D01*
X277556Y570385D01*
Y534734D01*
X276900Y534078D01*
Y513650D01*
X279450Y511100D01*
Y498191D01*
X275276Y494017D01*
G01X233850Y552201D02*
X235257Y553608D01*
Y562034D01*
X233050Y564241D01*
Y588365D01*
X238485Y593800D01*
X242333D01*
G01X254494Y529198D02*
X258200Y532904D01*
Y541094D01*
X252349Y546945D01*
Y548051D01*
X252295Y548105D01*
Y550534D01*
X249496Y553333D01*
Y576131D01*
X252301Y578936D01*
Y588188D01*
X255520Y591407D01*
X261070D01*
X264460Y594797D01*
Y605424D01*
X262360Y607524D01*
Y624180D01*
X269350Y631170D01*
Y651650D01*
X276100Y658400D01*
Y678700D01*
X277600Y680200D01*
G01X233447Y603747D02*
X233413D01*
X222300Y592634D01*
Y559086D01*
X216784Y553570D01*
X214593D01*
X212992Y551969D01*
G01X216141Y551970D02*
X216457D01*
X223900Y559413D01*
Y591900D01*
X232300Y600300D01*
G01X227100Y525400D02*
X228198Y526498D01*
Y541498D01*
X228800Y542100D01*
G01X238600Y509900D02*
Y511161D01*
X230072Y519689D01*
X227365D01*
X223250Y523804D01*
Y528716D01*
X225450Y530916D01*
Y549306D01*
X228313Y552169D01*
G01X233100Y509800D02*
X230888D01*
X217692Y522996D01*
Y546312D01*
X216785Y547219D01*
X214592D01*
X212992Y548819D01*
G01X275100Y509800D02*
Y534400D01*
X276056Y535356D01*
Y571056D01*
X278473Y573473D01*
Y574376D01*
X288550Y584453D01*
Y620562D01*
X280700Y628412D01*
Y645700D01*
X283870Y648870D01*
Y667482D01*
X288544Y672156D01*
Y685106D01*
X276400Y697250D01*
G01X260900Y553900D02*
Y555400D01*
X267100Y561600D01*
Y576200D01*
X266350Y576950D01*
Y579606D01*
X270520Y583776D01*
Y590037D01*
X273333Y592850D01*
X277737D01*
X279204Y591383D01*
X279214D01*
G01X286061Y502378D02*
X285450Y502989D01*
Y545078D01*
X283950Y546578D01*
Y559779D01*
X283975Y559804D01*
Y571131D01*
X285400Y572556D01*
G01X242600Y509800D02*
Y512819D01*
X230348Y525071D01*
Y529969D01*
X230863Y530484D01*
Y554927D01*
X233607Y557671D01*
G01X425765Y56265D02*
X427100Y54930D01*
Y24800D01*
X418500Y16200D01*
X377932D01*
X366488Y27644D01*
X329482D01*
X318970Y38156D01*
Y39398D01*
X318971Y39399D01*
Y130071D01*
X325850Y136950D01*
Y270050D01*
X328376Y272576D01*
Y281076D01*
X329974Y282674D01*
Y355101D01*
X326430Y358645D01*
Y392072D01*
X339450Y405092D01*
Y423682D01*
X330550Y432582D01*
Y436406D01*
X318219Y448737D01*
X305627D01*
X291601Y462763D01*
Y485544D01*
X304339Y498282D01*
Y506956D01*
X307400Y510017D01*
Y514867D01*
X306000Y516267D01*
Y519906D01*
X307400Y521306D01*
Y538571D01*
X315659Y546830D01*
Y560390D01*
X310965Y565084D01*
Y586115D01*
X311392Y586542D01*
Y594296D01*
X311500Y594404D01*
Y623300D01*
X320850Y632650D01*
Y642068D01*
X324962Y646180D01*
Y657462D01*
X328600Y661100D01*
G01X332200Y643800D02*
X330918D01*
X327900Y640782D01*
Y630680D01*
X319544Y622324D01*
Y600040D01*
X316814Y597310D01*
Y593354D01*
X315963Y592503D01*
Y577399D01*
X320451Y572911D01*
Y541922D01*
X317500Y538971D01*
Y526818D01*
X315900Y525218D01*
Y512200D01*
X314100Y510400D01*
Y505921D01*
X293101Y484922D01*
Y463385D01*
X306249Y450237D01*
X318841D01*
X332050Y437028D01*
Y433204D01*
X340950Y424304D01*
Y403546D01*
X330333Y392929D01*
Y391829D01*
X330332Y391828D01*
Y389342D01*
X330333Y389341D01*
Y356864D01*
X331474Y355723D01*
Y282052D01*
X329876Y280454D01*
Y271954D01*
X327466Y269544D01*
Y136381D01*
X320471Y129386D01*
Y38777D01*
X330104Y29144D01*
X372605D01*
X383698Y40237D01*
Y42723D01*
X383697Y42724D01*
Y43849D01*
X386026Y46178D01*
Y50800D01*
X395002Y59776D01*
X456460D01*
X456461Y59775D01*
X457703D01*
X467428Y69500D01*
X474951D01*
X498751Y93300D01*
X527401D01*
X543059Y108958D01*
G01X540800Y111500D02*
X524100Y94800D01*
X497924D01*
X474324Y71200D01*
X467006D01*
X457082Y61276D01*
X394380D01*
X384526Y51422D01*
Y46800D01*
X382197Y44471D01*
Y42102D01*
X382198Y42101D01*
Y40859D01*
X371983Y30644D01*
X330726D01*
X322050Y39320D01*
Y40562D01*
X322051Y40563D01*
Y128844D01*
X328966Y135759D01*
Y253566D01*
X337150Y261750D01*
Y367150D01*
X331833Y372467D01*
Y389963D01*
X331832Y389964D01*
Y391206D01*
X342450Y401824D01*
Y424926D01*
X333550Y433826D01*
Y437650D01*
X319463Y451737D01*
X306871D01*
X294601Y464007D01*
Y484300D01*
X315600Y505299D01*
Y509600D01*
X320400Y514400D01*
Y526600D01*
X319400Y527600D01*
Y538749D01*
X321951Y541300D01*
Y573533D01*
X320049Y575435D01*
Y576677D01*
X320050Y576678D01*
Y598058D01*
X321044Y599052D01*
Y604888D01*
X321421Y605265D01*
G01X343050Y438900D02*
Y437058D01*
X351450Y428658D01*
Y398092D01*
X346100Y392742D01*
Y386234D01*
X344080Y384214D01*
Y373541D01*
X346300Y371321D01*
Y213797D01*
X342000Y209497D01*
Y135949D01*
X331052Y125001D01*
Y43150D01*
X334558Y39644D01*
X368207D01*
X370060Y41497D01*
Y59860D01*
X380476Y70276D01*
X453350D01*
X463574Y80500D01*
X470892D01*
X501520Y111128D01*
X520609D01*
X530203Y120722D01*
Y157593D01*
X527953Y159843D01*
G01X542126Y154331D02*
X544376Y152081D01*
Y120722D01*
X521454Y97800D01*
X497924D01*
X497923Y97801D01*
X496681D01*
X473380Y74500D01*
X466062D01*
X455838Y64276D01*
X388624D01*
X379197Y54849D01*
Y42102D01*
X370739Y33644D01*
X331970D01*
X325051Y40563D01*
Y127600D01*
X331966Y134515D01*
Y232866D01*
X340300Y241200D01*
Y368833D01*
X338080Y371053D01*
Y385520D01*
X337100Y386500D01*
Y392230D01*
X345450Y400580D01*
Y426170D01*
X336550Y435070D01*
Y445577D01*
X334600Y447527D01*
Y455744D01*
X337750Y458894D01*
Y482696D01*
X319250Y501196D01*
Y508650D01*
X323600Y513000D01*
Y527700D01*
X324951Y529051D01*
Y574777D01*
X324709Y575019D01*
Y576500D01*
X323050Y578159D01*
Y596814D01*
X327280Y601044D01*
Y624810D01*
X338850Y636380D01*
Y653250D01*
X336650Y655450D01*
Y661550D01*
X336000Y662200D01*
G01X542126Y159843D02*
X545876Y156093D01*
Y120100D01*
X522076Y96300D01*
X497302D01*
X473702Y72700D01*
X466384D01*
X456460Y62776D01*
X389246D01*
X380697Y54227D01*
Y41480D01*
X371361Y32144D01*
X331348D01*
X323551Y39941D01*
Y128222D01*
X330466Y135137D01*
Y238166D01*
X338650Y246350D01*
Y368361D01*
X333333Y373678D01*
Y390585D01*
X343950Y401202D01*
Y425548D01*
X335050Y434448D01*
Y444955D01*
X333100Y446905D01*
Y456366D01*
X336250Y459516D01*
Y481411D01*
X317750Y499911D01*
Y509450D01*
X322100Y513800D01*
Y527051D01*
X320900Y528251D01*
Y537500D01*
X323451Y540051D01*
Y574155D01*
X321550Y576056D01*
Y597436D01*
X325779Y601665D01*
Y625431D01*
X332800Y632452D01*
Y640900D01*
X335800Y643900D01*
Y648400D01*
X336387Y648987D01*
G01X535039Y159055D02*
X537289Y156805D01*
Y123564D01*
X514526Y100801D01*
X496681D01*
X496680Y100802D01*
X495438D01*
X472136Y77500D01*
X464818D01*
X454594Y67276D01*
X387380D01*
X376197Y56093D01*
Y43346D01*
X369495Y36644D01*
X333314D01*
X328052Y41906D01*
Y126245D01*
X339000Y137193D01*
Y210741D01*
X343300Y215041D01*
Y370077D01*
X341080Y372297D01*
Y385458D01*
X343100Y387478D01*
Y393986D01*
X348450Y399336D01*
Y427414D01*
X339550Y436314D01*
Y446821D01*
X337600Y448771D01*
Y454500D01*
X340750Y457650D01*
Y484006D01*
X334800Y489956D01*
Y496800D01*
X335000Y497000D01*
G01X535039Y164567D02*
X538789Y160817D01*
Y122942D01*
X515148Y99301D01*
X496059D01*
X472758Y76000D01*
X465440D01*
X455216Y65776D01*
X388002D01*
X377697Y55471D01*
Y42724D01*
X370117Y35144D01*
X332692D01*
X326552Y41284D01*
Y126867D01*
X337500Y137815D01*
Y211363D01*
X341800Y215663D01*
Y369455D01*
X339580Y371675D01*
Y386142D01*
X338600Y387122D01*
Y391608D01*
X346950Y399958D01*
Y426792D01*
X338050Y435692D01*
Y446199D01*
X336100Y448149D01*
Y455122D01*
X339250Y458272D01*
Y483318D01*
X320750Y501818D01*
Y508028D01*
X325100Y512378D01*
Y527078D01*
X326451Y528429D01*
Y536502D01*
X329590Y539641D01*
Y540676D01*
X331551Y542637D01*
X331597D01*
X332698Y543738D01*
G01X535039Y178740D02*
X532200Y175901D01*
Y120597D01*
X521231Y109628D01*
X502142D01*
X471514Y79000D01*
X464196D01*
X453972Y68776D01*
X386576D01*
X374697Y56897D01*
Y44012D01*
X368829Y38144D01*
X333936D01*
X329552Y42528D01*
Y125623D01*
X340500Y136571D01*
Y210119D01*
X344800Y214419D01*
Y370699D01*
X342580Y372919D01*
Y384836D01*
X344600Y386856D01*
Y393364D01*
X349950Y398714D01*
Y428036D01*
X341050Y436936D01*
Y448050D01*
X339900Y449200D01*
Y454000D01*
G01X331900Y549700D02*
X332603Y548997D01*
X335279D01*
X340618Y543658D01*
Y538542D01*
X338918Y536842D01*
Y525424D01*
X337212Y523718D01*
Y519807D01*
X338900Y518119D01*
Y491514D01*
X344750Y485664D01*
Y451517D01*
X345101Y451166D01*
Y447473D01*
X345100Y447472D01*
Y445382D01*
X347242Y443240D01*
Y438524D01*
X355450Y430316D01*
Y392260D01*
X353050Y389860D01*
Y377604D01*
X350800Y375354D01*
Y368500D01*
X351400Y367900D01*
Y213239D01*
X346000Y207839D01*
Y179300D01*
X349500Y175800D01*
Y120601D01*
X380100Y90001D01*
Y78400D01*
X381590Y76910D01*
X400043D01*
X402677Y74276D01*
X451692D01*
X461916Y84500D01*
X469234D01*
X499862Y115128D01*
X516093D01*
X523116Y122151D01*
Y170979D01*
X520866Y173229D01*
G01Y178740D02*
X525116Y174490D01*
Y121322D01*
X516922Y113128D01*
X500691D01*
X470063Y82500D01*
X462745D01*
X452521Y72276D01*
X383224D01*
X378100Y77400D01*
Y89172D01*
X347500Y119772D01*
Y174971D01*
X344000Y178471D01*
Y208668D01*
X349400Y214068D01*
Y366900D01*
X348800Y367500D01*
Y376183D01*
X351050Y378433D01*
Y390689D01*
X353450Y393089D01*
Y429487D01*
X345242Y437695D01*
Y439800D01*
X343050Y441992D01*
Y450388D01*
X342750Y450688D01*
Y484835D01*
X336900Y490685D01*
Y503200D01*
X334892Y505208D01*
Y514908D01*
X335202Y515218D01*
Y518988D01*
X335031Y519159D01*
Y535784D01*
X338618Y539371D01*
Y542829D01*
X335033Y546414D01*
X332357D01*
X329899Y548872D01*
Y551466D01*
X329050Y552315D01*
G01X520866Y159055D02*
X518269Y156458D01*
Y120133D01*
X515264Y117128D01*
X499033D01*
X468405Y86500D01*
X461087D01*
X450863Y76276D01*
X403506D01*
X369105Y110677D01*
Y127716D01*
X357689Y139132D01*
Y180711D01*
X352350Y186050D01*
Y205208D01*
X357750Y210608D01*
Y370900D01*
X357150Y371500D01*
Y372723D01*
X359400Y374973D01*
Y387229D01*
X361800Y389629D01*
Y432947D01*
X353592Y441155D01*
Y445871D01*
X351451Y448012D01*
Y469933D01*
X351100Y470284D01*
Y493691D01*
X346929Y497862D01*
Y524181D01*
X348370Y525622D01*
Y563686D01*
X348220Y563836D01*
G01X448000Y80404D02*
X405036D01*
X373197Y112243D01*
Y130231D01*
X363662Y139766D01*
Y186700D01*
X359250Y191112D01*
Y206450D01*
X364000Y211200D01*
Y217700D01*
X361900Y219800D01*
Y369371D01*
X363400Y370871D01*
Y372139D01*
X365800Y374539D01*
Y434605D01*
X357592Y442813D01*
Y447529D01*
X355451Y449670D01*
Y471591D01*
X355100Y471942D01*
Y495349D01*
X351750Y498699D01*
Y515817D01*
X354771Y518838D01*
Y562943D01*
X343934Y573780D01*
Y593665D01*
X349650Y599381D01*
Y611694D01*
X349850Y611894D01*
Y613428D01*
X349650Y613628D01*
Y632065D01*
X344464Y637251D01*
Y654744D01*
X343372Y655836D01*
G01X344812Y563844D02*
X346654Y565686D01*
X349199D01*
X350370Y564515D01*
Y524793D01*
X348929Y523352D01*
Y498691D01*
X353100Y494520D01*
Y471113D01*
X353451Y470762D01*
Y448841D01*
X355592Y446700D01*
Y441984D01*
X363800Y433776D01*
Y388800D01*
X361400Y386400D01*
Y371700D01*
X359750Y370050D01*
Y209779D01*
X357250Y207279D01*
Y189650D01*
X361662Y185238D01*
Y137988D01*
X371105Y128545D01*
Y111506D01*
X404335Y78276D01*
X450034D01*
X460258Y88500D01*
X467576D01*
X498204Y119128D01*
X514435D01*
X516269Y120962D01*
Y159970D01*
X520866Y164567D01*
G01X293600Y518400D02*
X290800D01*
X289800Y519400D01*
Y533600D01*
X288000Y535400D01*
Y561000D01*
G01X347013Y656090D02*
Y645181D01*
X346464Y644632D01*
Y638080D01*
X351650Y632894D01*
Y614457D01*
X351850Y614257D01*
Y611065D01*
X351650Y610865D01*
Y598552D01*
X345934Y592836D01*
Y574609D01*
X356771Y563772D01*
Y518009D01*
X353750Y514988D01*
Y504035D01*
X356150Y501635D01*
Y497128D01*
X357100Y496178D01*
Y472771D01*
X357451Y472420D01*
Y450499D01*
X359592Y448358D01*
Y443642D01*
X367800Y435434D01*
Y373710D01*
X365400Y371310D01*
Y370042D01*
X363900Y368542D01*
Y250164D01*
X366000Y248064D01*
Y209808D01*
X361400Y205208D01*
Y191791D01*
X365662Y187529D01*
Y140596D01*
X375199Y131059D01*
Y113070D01*
X405865Y82404D01*
X444800D01*
G01X293326Y494174D02*
X300994Y501842D01*
Y509706D01*
X303500Y512212D01*
Y520235D01*
X305400Y522135D01*
Y539400D01*
X313659Y547659D01*
Y559561D01*
X308965Y564255D01*
Y586944D01*
X309392Y587371D01*
Y595125D01*
X309500Y595233D01*
Y624129D01*
X318800Y633429D01*
Y649788D01*
X319450Y650438D01*
Y655396D01*
X332554Y668500D01*
Y681589D01*
X329062Y685081D01*
Y700612D01*
X328087Y701587D01*
G01X288311Y496200D02*
X289800D01*
X298994Y505394D01*
Y510535D01*
X301500Y513041D01*
Y521064D01*
X303400Y522964D01*
Y528800D01*
X300656Y531544D01*
Y552120D01*
X302127Y553591D01*
Y578027D01*
X305563Y581463D01*
Y599549D01*
X307320Y601306D01*
Y624778D01*
X314950Y632408D01*
Y660234D01*
X330206Y675490D01*
Y681108D01*
X327062Y684252D01*
Y697600D01*
G01X298200Y521100D02*
X297644D01*
X296001Y522743D01*
Y523635D01*
X295522Y524114D01*
Y536941D01*
X294369Y538094D01*
Y562709D01*
X296356Y564696D01*
Y599974D01*
X295150Y601180D01*
Y623950D01*
X293500Y625600D01*
G01X301300Y524400D02*
X298022Y527678D01*
Y537977D01*
X296869Y539130D01*
Y544704D01*
X298104Y545939D01*
Y553104D01*
X299627Y554627D01*
Y587027D01*
X301000Y588400D01*
Y598866D01*
X297650Y602216D01*
Y625050D01*
X293600Y629100D01*
G01X327800Y514900D02*
X327592D01*
X326800Y515692D01*
Y526656D01*
X327951Y527807D01*
Y535880D01*
X331090Y539019D01*
Y540054D01*
X332173Y541137D01*
X335755D01*
X336618Y542000D01*
X336723D01*
G01X323400Y507540D02*
X330000Y514140D01*
Y517100D01*
X328300Y518800D01*
Y525127D01*
X330200Y527027D01*
Y531800D01*
G01X300700Y667000D02*
X296500D01*
X292700Y663200D01*
Y654330D01*
X286870Y648500D01*
Y628230D01*
X291847Y623253D01*
Y582454D01*
X293856Y580445D01*
Y569391D01*
X290350Y565885D01*
Y538412D01*
X292700Y536062D01*
Y523400D01*
X293500Y522600D01*
G01X309600Y520150D02*
Y524880D01*
X309450Y525030D01*
Y536350D01*
X312300Y539200D01*
Y540600D01*
G01X333400Y503800D02*
X332892Y504308D01*
Y515737D01*
X333202Y516047D01*
Y518159D01*
X332940Y518421D01*
Y539287D01*
G01X325899Y589186D02*
X326879Y588206D01*
Y548882D01*
X327417Y548344D01*
G01X352716Y594135D02*
X350622Y592041D01*
Y578250D01*
X353500Y575372D01*
Y569872D01*
X358771Y564601D01*
Y517180D01*
X358150Y516559D01*
Y497957D01*
X359100Y497007D01*
Y473600D01*
X359600Y473100D01*
Y451800D01*
X359400Y451600D01*
G01X288720Y641455D02*
X288900Y641275D01*
Y637883D01*
X302736Y624047D01*
Y618750D01*
X305320Y616166D01*
Y602135D01*
X303536Y600351D01*
Y587336D01*
X303000Y586800D01*
G01X338135Y670511D02*
X338143D01*
X338150Y670504D01*
Y656750D01*
X340350Y654550D01*
Y635758D01*
X328780Y624188D01*
Y595978D01*
X325761Y592959D01*
G01X342208Y714950D02*
X342542Y714616D01*
Y685983D01*
G01X342645Y682506D02*
X340250Y684901D01*
Y717049D01*
X337481Y719818D01*
G01X442913Y159843D02*
X438600Y155530D01*
Y125969D01*
X432035Y119404D01*
X421201D01*
X415053Y125552D01*
Y161913D01*
X394500Y182466D01*
Y475856D01*
X391300Y479056D01*
Y486626D01*
X395622Y490948D01*
Y501578D01*
X391767Y505433D01*
Y512956D01*
X392900Y514089D01*
Y532144D01*
X391600Y533444D01*
Y537943D01*
X398965Y545308D01*
Y654134D01*
X394000Y659099D01*
Y663600D01*
X395500Y665100D01*
Y688398D01*
X380598Y703300D01*
X379100D01*
G01X457086Y159843D02*
Y157850D01*
X459336Y155600D01*
Y114569D01*
X446171Y101404D01*
X413740D01*
X394706Y120438D01*
Y139018D01*
X385000Y148724D01*
Y261600D01*
X383061Y263539D01*
Y321424D01*
X387500Y325863D01*
Y458200D01*
G01X399900Y152100D02*
Y144800D01*
X402303Y142397D01*
Y122742D01*
X416641Y108404D01*
X443270D01*
X454750Y119884D01*
Y151995D01*
X457086Y154331D01*
G01X389081Y475224D02*
X391500Y472805D01*
Y181222D01*
X412053Y160669D01*
Y124308D01*
X419957Y116404D01*
X442967D01*
X446800Y120237D01*
Y161367D01*
X450000Y164567D01*
G01X387950Y466800D02*
Y462450D01*
X385000Y459500D01*
Y326899D01*
X380561Y322460D01*
Y261039D01*
X382500Y259100D01*
Y147688D01*
X392205Y137983D01*
Y119403D01*
X412704Y98904D01*
X447207D01*
X461836Y113533D01*
Y163754D01*
X457086Y168504D01*
G01X428740Y174016D02*
X424612Y169888D01*
Y126155D01*
X422585Y124128D01*
X420721D01*
X418053Y126796D01*
Y163157D01*
X397500Y183710D01*
Y482752D01*
X394952Y485300D01*
G01X398000Y165400D02*
X394000Y161400D01*
Y143771D01*
X397803Y139968D01*
Y120877D01*
X414776Y103904D01*
X445135D01*
X455766Y114535D01*
G01X398050Y162000D02*
X396000Y159950D01*
Y144600D01*
X399803Y140797D01*
Y121706D01*
X415605Y105904D01*
X444306D01*
X456202Y117800D01*
X457000D01*
G01X370900Y471700D02*
X369600Y470400D01*
Y455100D01*
X368400Y453900D01*
Y445442D01*
X375300Y438542D01*
Y370509D01*
X372900Y368109D01*
Y366934D01*
X371400Y365434D01*
Y254300D01*
X373500Y252200D01*
Y206700D01*
X370318Y203518D01*
Y201018D01*
X373162Y198174D01*
Y143704D01*
X382699Y134167D01*
Y116178D01*
X408973Y89904D01*
X451054D01*
X473221Y112071D01*
X480538D01*
G01X376910Y366078D02*
Y365139D01*
X375400Y363629D01*
Y333829D01*
X377798Y331431D01*
Y326846D01*
X375400Y324448D01*
Y256600D01*
X377500Y254500D01*
Y145615D01*
X386700Y136415D01*
Y134759D01*
X386699Y134758D01*
Y117836D01*
X410631Y93904D01*
X449396D01*
X473510Y118018D01*
Y152081D01*
X471260Y154331D01*
G01X406400Y150300D02*
X409053Y147647D01*
Y123064D01*
X418713Y113404D01*
X444734D01*
X448996Y117666D01*
G01X464173Y173229D02*
X466423Y170979D01*
Y115291D01*
X448036Y96904D01*
X411875D01*
X390205Y118574D01*
Y137154D01*
X380500Y146859D01*
Y257800D01*
X378561Y259739D01*
Y323365D01*
X380798Y325602D01*
Y332824D01*
X378561Y335061D01*
Y349000D01*
X383000Y353439D01*
Y460329D01*
X385300Y462629D01*
Y492355D01*
X387267Y494322D01*
Y516643D01*
X387700Y517076D01*
Y517700D01*
G01X378200Y476600D02*
X377426Y475826D01*
Y455393D01*
X381300Y451519D01*
Y353861D01*
X376900Y349461D01*
Y334600D01*
X379298Y332202D01*
Y326224D01*
X376900Y323826D01*
Y258000D01*
X379000Y255900D01*
Y146237D01*
X388200Y137037D01*
Y118457D01*
X411253Y95404D01*
X448658D01*
X467923Y114669D01*
Y174990D01*
X464173Y178740D01*
G01X371457Y667593D02*
Y660451D01*
X379388Y652520D01*
Y639360D01*
X374850Y634822D01*
Y606949D01*
X364874Y596973D01*
Y596237D01*
X361450Y592813D01*
Y584850D01*
X362900Y583400D01*
Y576199D01*
X360400Y573699D01*
Y570044D01*
X363771Y566673D01*
Y560865D01*
X368550Y556086D01*
Y528367D01*
X369350Y527567D01*
Y520686D01*
X364516Y515852D01*
Y499474D01*
X365700Y498290D01*
Y473578D01*
X364800Y472678D01*
Y453100D01*
X365900Y452000D01*
Y444406D01*
X372800Y437506D01*
Y371638D01*
X370400Y369238D01*
Y367970D01*
X368900Y366470D01*
Y253200D01*
X371000Y251100D01*
Y207736D01*
X367818Y204554D01*
Y199982D01*
X370662Y197138D01*
Y142668D01*
X380199Y133131D01*
Y115142D01*
X407937Y87404D01*
X452090D01*
X458186Y93500D01*
X465504D01*
X496132Y124128D01*
X507625D01*
X508943Y125446D01*
Y155007D01*
X513779Y159843D01*
G01X368060Y667743D02*
X368801Y667002D01*
Y659571D01*
X376836Y651536D01*
Y640548D01*
X374699Y638411D01*
X369017D01*
X363214Y632608D01*
Y627700D01*
X361600Y626086D01*
Y596499D01*
X358950Y593849D01*
Y576350D01*
X357200Y574600D01*
Y569708D01*
X361271Y565637D01*
Y559829D01*
X364651Y556449D01*
Y547330D01*
X362150Y544829D01*
Y517022D01*
X360650Y515522D01*
Y498993D01*
X363200Y496443D01*
Y474614D01*
X362100Y473514D01*
Y450764D01*
X362092Y450756D01*
Y444678D01*
X370300Y436470D01*
Y372674D01*
X367900Y370274D01*
Y369006D01*
X366400Y367506D01*
Y251600D01*
X368500Y249500D01*
Y208772D01*
X363900Y204172D01*
Y192827D01*
X368162Y188565D01*
Y141632D01*
X377699Y132095D01*
Y114106D01*
X406901Y84904D01*
X453126D01*
X459222Y91000D01*
X466540D01*
X497168Y121628D01*
X508662D01*
X510125Y123091D01*
Y123092D01*
X511444Y124411D01*
Y151996D01*
X513779Y154331D01*
G01X471260Y159843D02*
X475510Y155593D01*
Y117189D01*
X450225Y91904D01*
X409802D01*
X384699Y117007D01*
Y135587D01*
X375500Y144786D01*
Y253200D01*
X373400Y255300D01*
Y325277D01*
X375798Y327675D01*
Y330602D01*
X373400Y333000D01*
Y364605D01*
X374900Y366105D01*
Y367280D01*
X377300Y369680D01*
Y439371D01*
X370400Y446271D01*
Y453071D01*
X371600Y454271D01*
Y467200D01*
X373426Y469026D01*
Y479326D01*
X375598Y481498D01*
Y493969D01*
X379267Y497638D01*
Y542021D01*
X380467Y543221D01*
Y572134D01*
X373700Y578901D01*
Y585223D01*
X380572Y592095D01*
G01X398600Y662700D02*
X400465Y660835D01*
Y544686D01*
X393100Y537321D01*
Y534066D01*
X394400Y532766D01*
Y513467D01*
X393267Y512334D01*
Y506055D01*
X397122Y502200D01*
Y490326D01*
X392800Y486004D01*
Y479678D01*
X396000Y476478D01*
Y183088D01*
X416553Y162535D01*
Y126174D01*
X420099Y122628D01*
X423207D01*
X426112Y125533D01*
Y151703D01*
X428740Y154331D01*
G01X390769Y495379D02*
Y492461D01*
X386800Y488492D01*
Y474300D01*
X390000Y471100D01*
Y180600D01*
X410553Y160047D01*
Y123686D01*
X419335Y114904D01*
X443589D01*
X452250Y123565D01*
Y169180D01*
X457086Y174016D01*
G01X442913D02*
X445163Y171766D01*
Y120722D01*
X442345Y117904D01*
X420579D01*
X413553Y124930D01*
Y161291D01*
X393000Y181844D01*
Y475234D01*
X389800Y478434D01*
Y487248D01*
X394122Y491570D01*
Y500900D01*
X390267Y504755D01*
Y513578D01*
X391400Y514711D01*
Y531522D01*
X390100Y532822D01*
Y539418D01*
X393889Y543207D01*
G01X397650Y508250D02*
X400500Y505400D01*
Y184954D01*
X412225Y173229D01*
X421653D01*
G01X397650Y536671D02*
X402000Y532321D01*
Y185576D01*
X408836Y178740D01*
X421653D01*
G01X401000Y676500D02*
X401965Y675535D01*
Y544064D01*
X395600Y537699D01*
Y533688D01*
X400500Y528788D01*
Y515600D01*
X394767Y509867D01*
Y506677D01*
X399000Y502444D01*
Y184332D01*
X415912Y167420D01*
X418800D01*
X421653Y164567D01*
G01X383126Y565162D02*
X389250Y559038D01*
Y544871D01*
X381267Y536888D01*
Y496809D01*
X377598Y493140D01*
Y480669D01*
X375426Y478497D01*
Y451374D01*
X375880Y450920D01*
Y447850D01*
X374847Y446817D01*
Y444653D01*
X379300Y440200D01*
Y364700D01*
X377300Y362700D01*
G01X366700Y454800D02*
X367300Y455400D01*
Y471642D01*
X368200Y472542D01*
Y496800D01*
X370780Y499380D01*
Y512117D01*
X370644Y512253D01*
Y518261D01*
X371850Y519467D01*
Y528603D01*
X371050Y529403D01*
Y545403D01*
X372749Y547102D01*
Y566915D01*
X365400Y574264D01*
Y584436D01*
X363950Y585886D01*
Y590454D01*
X364300Y590804D01*
Y592900D01*
G01X380200Y457800D02*
X379426Y458574D01*
Y470126D01*
X381300Y472000D01*
Y494013D01*
X383267Y495980D01*
Y520967D01*
X387800Y525500D01*
G01X381400Y462000D02*
X383300Y463900D01*
Y493184D01*
X385267Y495151D01*
Y519167D01*
X387700Y521600D01*
G01X364600Y670800D02*
X370867D01*
X374700Y666967D01*
Y660744D01*
X381888Y653556D01*
Y638324D01*
X379601Y636037D01*
Y626174D01*
X377350Y623923D01*
Y603065D01*
X368400Y594115D01*
Y574800D01*
X375249Y567951D01*
Y546066D01*
X374767Y545584D01*
Y499831D01*
X370720Y495784D01*
Y481813D01*
X370800Y481733D01*
Y475128D01*
G01X389081Y475224D02*
X388300Y476005D01*
Y487870D01*
X392622Y492192D01*
Y500278D01*
X388767Y504133D01*
Y514200D01*
X389900Y515333D01*
Y530900D01*
X388600Y532200D01*
Y541392D01*
X391379Y544171D01*
Y559850D01*
X385900Y565329D01*
Y569902D01*
X375700Y580102D01*
G01X373700Y482700D02*
X373220Y483180D01*
Y494420D01*
X377267Y498467D01*
Y542967D01*
X377384D01*
X378467Y544050D01*
Y545584D01*
X377749Y546302D01*
Y568987D01*
X370900Y575836D01*
Y593079D01*
X379850Y602029D01*
Y614750D01*
X390600Y625500D01*
G01X394880Y548670D02*
X395465Y549255D01*
Y564671D01*
X391700Y568436D01*
Y619599D01*
X395465Y623364D01*
Y652095D01*
X390500Y657060D01*
Y665800D01*
G01X393465Y553100D02*
Y560593D01*
X389700Y564358D01*
Y620699D01*
X392600Y623599D01*
Y652131D01*
X388400Y656331D01*
Y667100D01*
X390500Y669200D01*
G01X396400Y545500D02*
X397465Y546565D01*
Y575835D01*
X396150Y577150D01*
Y577367D01*
X395067Y578450D01*
X394850D01*
X393700Y579600D01*
Y600900D01*
X397465Y604665D01*
Y652924D01*
X392500Y657889D01*
Y664222D01*
X394000Y665722D01*
Y687281D01*
X390355Y690926D01*
G01X361914Y680181D02*
X369018D01*
X381966Y667233D01*
Y659936D01*
X390600Y651302D01*
Y625500D01*
G01X363664Y688950D02*
X363785D01*
X384466Y668269D01*
Y661650D01*
G01X390355Y690926D02*
X383781Y697500D01*
X378600D01*
X373140Y702960D01*
X373060D01*
G01X515700Y50899D02*
X514261D01*
X513260Y51900D01*
X487489D01*
X485620Y50031D01*
X472831D01*
X472800Y50000D01*
G01X469000Y50100D02*
X473000Y54100D01*
X514333D01*
X515785Y55552D01*
G01X458041Y47341D02*
X458100Y47400D01*
Y48229D01*
X461121Y51250D01*
X463728D01*
X470678Y58200D01*
X502300D01*
G01X531050Y46998D02*
Y52560D01*
X519760Y63850D01*
X512551D01*
X509201Y60500D01*
X476100D01*
G01X528300Y58648D02*
X521098Y65850D01*
X511722D01*
X508672Y62800D01*
X478700D01*
G01X462372Y49179D02*
X464486D01*
X471407Y56100D01*
X512600D01*
X515500Y59000D01*
G01X642998Y127863D02*
X642093Y126958D01*
X632214D01*
X572596Y67340D01*
Y25436D01*
X572597Y25435D01*
Y24789D01*
X566191Y18383D01*
X513136D01*
X511232Y20287D01*
X495250D01*
X494242Y21295D01*
Y23887D01*
X496355Y26000D01*
G01X496242Y22287D02*
X512061D01*
X513965Y20383D01*
X565362D01*
X570596Y25617D01*
Y68169D01*
X631814Y129387D01*
X640118D01*
X642574Y131843D01*
G01X486700Y31100D02*
Y20578D01*
X491078Y16200D01*
X567783D01*
X579668Y28085D01*
Y32418D01*
X581640Y34390D01*
X585685D01*
X604975Y15100D01*
X683800D01*
X697000Y28300D01*
X777641D01*
X787658Y38317D01*
X824379D01*
X840422Y54360D01*
Y150574D01*
X842022Y152174D01*
G01X478590Y70310D02*
X499580Y91300D01*
X528230D01*
X551462Y114532D01*
Y170979D01*
X549212Y173229D01*
G01X482200Y70500D02*
Y71000D01*
X500500Y89300D01*
X529059D01*
X553462Y113703D01*
Y174490D01*
X549212Y178740D01*
G01X532500Y58600D02*
X528814Y62286D01*
Y86226D01*
X558549Y115961D01*
Y157593D01*
X556299Y159843D01*
G01X759342Y543603D02*
X757613D01*
X753680Y539670D01*
X707970D01*
X703840Y535540D01*
X668067D01*
X646840Y514313D01*
Y484579D01*
X673044Y458375D01*
Y418118D01*
X646840Y391914D01*
Y77117D01*
X678150Y45807D01*
Y19650D01*
X680300Y17500D01*
G01X849420Y407748D02*
X840048D01*
X822300Y390000D01*
G54D14*
X265400Y446100D03*
X753800Y535000D03*
G54D24*
G01X-9023Y-84471D02*
X-8149Y-83596D01*
X-7494Y-82138D01*
X-7057Y-80095D01*
X-7494Y-78346D01*
X-8367Y-77179D01*
X-9896Y-76304D01*
X-15791D01*
Y-93804D01*
X-8586D01*
X-7057Y-92638D01*
X-6184Y-90887D01*
X-5747Y-88846D01*
X-6184Y-86804D01*
X-7494Y-85054D01*
X-9023Y-84471D01*
X-15791D01*
G01X3674Y-93804D02*
Y-82138D01*
G01Y-84471D02*
X4766Y-83304D01*
X5858Y-82429D01*
X7386Y-82138D01*
X8477Y-82429D01*
X9788Y-83304D01*
G01X19646Y-99054D02*
X20956Y-99637D01*
X22703Y-99054D01*
X23794Y-97888D01*
X24668Y-96429D01*
X25977Y-91763D01*
X28816Y-82138D01*
G01X21829D02*
X25977Y-91763D01*
G01X45224Y-83596D02*
X43696Y-82429D01*
X42386Y-82138D01*
X40639Y-82721D01*
X39329Y-83887D01*
X38456Y-85929D01*
X38237Y-87971D01*
X38456Y-90013D01*
X39329Y-91763D01*
X40639Y-93221D01*
X42386Y-93804D01*
X43914Y-93221D01*
X45224Y-92054D01*
G01X55956Y-85929D02*
X62943D01*
X62288Y-83887D01*
X61196Y-82721D01*
X59668Y-82138D01*
X58139Y-82429D01*
X56829Y-83304D01*
X55956Y-85346D01*
X55519Y-87096D01*
Y-88846D01*
X55956Y-90596D01*
X57048Y-92346D01*
X58358Y-93512D01*
X59886Y-93804D01*
X61414Y-93221D01*
X62943Y-91471D01*
G01X99034Y-77763D02*
X97724Y-76887D01*
X96196Y-76304D01*
X94449D01*
X92484Y-77179D01*
X90956Y-78637D01*
X89864Y-80388D01*
X88991Y-83304D01*
X88772Y-85929D01*
X89209Y-88554D01*
X89864Y-90304D01*
X91174Y-92054D01*
X92703Y-93221D01*
X94231Y-93804D01*
X95759D01*
X97288Y-93221D01*
X98598Y-92346D01*
X99690Y-91180D01*
G01X115661Y-93804D02*
Y-82138D01*
G01Y-84179D02*
X114788Y-83013D01*
X113477Y-82429D01*
X111949Y-82138D01*
X110421Y-82721D01*
X109111Y-83887D01*
X108237Y-85637D01*
X107801Y-87971D01*
X108237Y-90304D01*
X109111Y-92054D01*
X110421Y-93221D01*
X111949Y-93804D01*
X113477Y-93512D01*
X114788Y-92638D01*
X115661Y-91471D01*
G01X125519Y-93804D02*
Y-82138D01*
G01Y-85054D02*
X126393Y-83596D01*
X127703Y-82429D01*
X129449Y-82138D01*
X130977Y-82429D01*
X132288Y-83596D01*
X132943Y-85637D01*
Y-93804D01*
G01X142146Y-99054D02*
X143456Y-99637D01*
X145203Y-99054D01*
X146294Y-97888D01*
X147168Y-96429D01*
X148477Y-91763D01*
X151316Y-82138D01*
G01X144329D02*
X148477Y-91763D01*
G01X164231Y-93804D02*
X162921Y-93512D01*
X161611Y-92346D01*
X160737Y-90304D01*
X160301Y-87971D01*
X160737Y-85637D01*
X161611Y-83596D01*
X162921Y-82429D01*
X164231Y-82138D01*
X165541Y-82429D01*
X166851Y-83596D01*
X167724Y-85637D01*
X167943Y-87971D01*
X167724Y-90304D01*
X166851Y-92346D01*
X165541Y-93512D01*
X164231Y-93804D01*
G01X178019D02*
Y-82138D01*
G01Y-85054D02*
X178893Y-83596D01*
X180203Y-82429D01*
X181949Y-82138D01*
X183477Y-82429D01*
X184788Y-83596D01*
X185443Y-85637D01*
Y-93804D01*
G01X214111Y-76304D02*
X219351D01*
G01X216731D02*
Y-93804D01*
G01X214111D02*
X219351D01*
G01X234231D02*
X232484Y-93512D01*
X230956Y-92346D01*
X229646Y-90596D01*
X228772Y-88554D01*
X228336Y-86221D01*
Y-83887D01*
X228772Y-81554D01*
X229646Y-79512D01*
X230956Y-77763D01*
X232484Y-76596D01*
X234231Y-76304D01*
X235977Y-76596D01*
X237506Y-77763D01*
X238816Y-79512D01*
X239690Y-81554D01*
X240126Y-83887D01*
Y-86221D01*
X239690Y-88554D01*
X238816Y-90596D01*
X237506Y-92346D01*
X235977Y-93512D01*
X234231Y-93804D01*
G01X246054D02*
Y-76304D01*
X251731Y-90887D01*
X257408Y-76304D01*
Y-93804D01*
G01X285639Y-99637D02*
X283456Y-96721D01*
X282364Y-93804D01*
Y-82138D01*
X283456Y-79221D01*
X285639Y-76304D01*
G01X298554Y-93804D02*
Y-76304D01*
X304231Y-90887D01*
X309908Y-76304D01*
Y-93804D01*
G01X321731Y-94387D02*
X321294Y-94096D01*
Y-93512D01*
X321731Y-93221D01*
X322168Y-93512D01*
Y-94096D01*
X321731Y-94387D01*
G01X335083Y-79221D02*
X336393Y-77471D01*
X337921Y-76596D01*
X339668Y-76304D01*
X341851Y-76887D01*
X343379Y-78346D01*
X343816Y-80095D01*
X343598Y-81846D01*
X342724Y-83304D01*
X338358Y-86221D01*
X336393Y-88262D01*
X335083Y-91180D01*
X334646Y-93804D01*
X343816D01*
G01X374231D02*
X372921Y-93512D01*
X371611Y-92346D01*
X370737Y-90304D01*
X370301Y-87971D01*
X370737Y-85637D01*
X371611Y-83596D01*
X372921Y-82429D01*
X374231Y-82138D01*
X375541Y-82429D01*
X376851Y-83596D01*
X377724Y-85637D01*
X377943Y-87971D01*
X377724Y-90304D01*
X376851Y-92346D01*
X375541Y-93512D01*
X374231Y-93804D01*
G01X388019D02*
Y-82138D01*
G01Y-85054D02*
X388893Y-83596D01*
X390203Y-82429D01*
X391949Y-82138D01*
X393477Y-82429D01*
X394788Y-83596D01*
X395443Y-85637D01*
Y-93804D01*
G01X409231D02*
Y-76304D01*
G01X422146Y-99054D02*
X423456Y-99637D01*
X425203Y-99054D01*
X426294Y-97888D01*
X427168Y-96429D01*
X428477Y-91763D01*
X431316Y-82138D01*
G01X424329D02*
X428477Y-91763D01*
G01X445323Y-99637D02*
X447506Y-96721D01*
X448598Y-93804D01*
Y-82138D01*
X447506Y-79221D01*
X445323Y-76304D01*
G01X176054Y-48804D02*
Y-31304D01*
X181731Y-45887D01*
X187408Y-31304D01*
Y-48804D01*
G01X199231D02*
X197921Y-48512D01*
X196611Y-47346D01*
X195737Y-45304D01*
X195301Y-42971D01*
X195737Y-40637D01*
X196611Y-38596D01*
X197921Y-37429D01*
X199231Y-37138D01*
X200541Y-37429D01*
X201851Y-38596D01*
X202724Y-40637D01*
X202943Y-42971D01*
X202724Y-45304D01*
X201851Y-47346D01*
X200541Y-48512D01*
X199231Y-48804D01*
G01X220661Y-31304D02*
Y-48804D01*
G01Y-46180D02*
X219788Y-47638D01*
X218477Y-48512D01*
X216949Y-48804D01*
X215203Y-48221D01*
X213893Y-46763D01*
X213019Y-45013D01*
X212801Y-42971D01*
X213019Y-40929D01*
X213893Y-39179D01*
X215203Y-37721D01*
X216949Y-37138D01*
X218477Y-37429D01*
X219569Y-38013D01*
X220661Y-39179D01*
G01X230956Y-40929D02*
X237943D01*
X237288Y-38887D01*
X236196Y-37721D01*
X234668Y-37138D01*
X233139Y-37429D01*
X231829Y-38304D01*
X230956Y-40346D01*
X230519Y-42096D01*
Y-43846D01*
X230956Y-45596D01*
X232048Y-47346D01*
X233358Y-48512D01*
X234886Y-48804D01*
X236414Y-48221D01*
X237943Y-46471D01*
G01X251731Y-48804D02*
Y-31304D01*
G01X504231Y-93804D02*
Y-76304D01*
X501611Y-79804D01*
G01Y-93804D02*
X506851D01*
G01X517583Y-86513D02*
X519111Y-84471D01*
X520421Y-83304D01*
X522168Y-82721D01*
X523696Y-83304D01*
X524788Y-84471D01*
X525661Y-86221D01*
X525879Y-88262D01*
X525661Y-90013D01*
X524788Y-91763D01*
X523477Y-93221D01*
X521949Y-93804D01*
X520203Y-93221D01*
X518674Y-91471D01*
X517801Y-88846D01*
X517583Y-85929D01*
X518019Y-82138D01*
X518674Y-80095D01*
X519766Y-78054D01*
X521294Y-76596D01*
X522823Y-76304D01*
X524351Y-76887D01*
X525443Y-78346D01*
G01X534428Y-90304D02*
X535737Y-92346D01*
X537484Y-93512D01*
X539449Y-93804D01*
X541196Y-93512D01*
X542943Y-92054D01*
X544034Y-90304D01*
X544253Y-88554D01*
X543816Y-86513D01*
X542288Y-85054D01*
X540759Y-84471D01*
X538794D01*
G01X540759D02*
X542069Y-83596D01*
X543161Y-82138D01*
X543598Y-80388D01*
X543161Y-78637D01*
X542069Y-77179D01*
X540104Y-76304D01*
X538139Y-76596D01*
X536174Y-77763D01*
G01X559351Y-93804D02*
Y-76304D01*
X551272Y-88846D01*
X562190D01*
G01X570083Y-79221D02*
X571393Y-77471D01*
X572921Y-76596D01*
X574668Y-76304D01*
X576851Y-76887D01*
X578379Y-78346D01*
X578816Y-80095D01*
X578598Y-81846D01*
X577724Y-83304D01*
X573358Y-86221D01*
X571393Y-88262D01*
X570083Y-91180D01*
X569646Y-93804D01*
X578816D01*
G01X491114Y-48804D02*
Y-31304D01*
X496354D01*
X498101Y-32179D01*
X499411Y-34221D01*
X499848Y-36554D01*
X499411Y-38887D01*
X498319Y-40637D01*
X496354Y-41513D01*
X491114D01*
G01X517784Y-32763D02*
X516474Y-31887D01*
X514946Y-31304D01*
X513199D01*
X511234Y-32179D01*
X509706Y-33637D01*
X508614Y-35388D01*
X507741Y-38304D01*
X507522Y-40929D01*
X507959Y-43554D01*
X508614Y-45304D01*
X509924Y-47054D01*
X511453Y-48221D01*
X512981Y-48804D01*
X514509D01*
X516038Y-48221D01*
X517348Y-47346D01*
X518440Y-46180D01*
G01X532227Y-39471D02*
X533101Y-38596D01*
X533756Y-37138D01*
X534193Y-35095D01*
X533756Y-33346D01*
X532883Y-32179D01*
X531354Y-31304D01*
X525459D01*
Y-48804D01*
X532664D01*
X534193Y-47638D01*
X535066Y-45887D01*
X535503Y-43846D01*
X535066Y-41804D01*
X533756Y-40054D01*
X532227Y-39471D01*
X525459D01*
G01X541431Y-54637D02*
X554531D01*
G01X560459Y-48804D02*
Y-31304D01*
X570503Y-48804D01*
Y-31304D01*
G01X582981Y-48804D02*
X581234Y-48512D01*
X579706Y-47346D01*
X578396Y-45596D01*
X577522Y-43554D01*
X577086Y-41221D01*
Y-38887D01*
X577522Y-36554D01*
X578396Y-34512D01*
X579706Y-32763D01*
X581234Y-31596D01*
X582981Y-31304D01*
X584727Y-31596D01*
X586256Y-32763D01*
X587566Y-34512D01*
X588440Y-36554D01*
X588876Y-38887D01*
Y-41221D01*
X588440Y-43554D01*
X587566Y-45596D01*
X586256Y-47346D01*
X584727Y-48512D01*
X582981Y-48804D01*
G01X633822Y-31304D02*
X639281Y-48804D01*
X644740Y-31304D01*
G01X661148Y-48804D02*
X652414D01*
Y-31304D01*
X661148D01*
G01X657654Y-39762D02*
X652414D01*
G01X669914Y-48804D02*
Y-31304D01*
X675373D01*
X677119Y-32179D01*
X678211Y-33346D01*
X678648Y-35679D01*
X678211Y-38013D01*
X676901Y-39471D01*
X675373Y-40346D01*
X669914D01*
G01X675373D02*
X678648Y-48804D01*
G01X691781Y-49387D02*
X691344Y-49096D01*
Y-48512D01*
X691781Y-48221D01*
X692218Y-48512D01*
Y-49096D01*
X691781Y-49387D01*
G01X661383Y-79221D02*
X662693Y-77471D01*
X664221Y-76596D01*
X665968Y-76304D01*
X668151Y-76887D01*
X669679Y-78346D01*
X670116Y-80095D01*
X669898Y-81846D01*
X669024Y-83304D01*
X664658Y-86221D01*
X662693Y-88262D01*
X661383Y-91180D01*
X660946Y-93804D01*
X670116D01*
G01X767364Y-31304D02*
Y-48804D01*
X776098D01*
G01X793161D02*
Y-37138D01*
G01Y-39179D02*
X792288Y-38013D01*
X790977Y-37429D01*
X789449Y-37138D01*
X787921Y-37721D01*
X786611Y-38887D01*
X785737Y-40637D01*
X785301Y-42971D01*
X785737Y-45304D01*
X786611Y-47054D01*
X787921Y-48221D01*
X789449Y-48804D01*
X790977Y-48512D01*
X792288Y-47638D01*
X793161Y-46471D01*
G01X802146Y-54054D02*
X803456Y-54637D01*
X805203Y-54054D01*
X806294Y-52888D01*
X807168Y-51429D01*
X808477Y-46763D01*
X811316Y-37138D01*
G01X804329D02*
X808477Y-46763D01*
G01X820956Y-40929D02*
X827943D01*
X827288Y-38887D01*
X826196Y-37721D01*
X824668Y-37138D01*
X823139Y-37429D01*
X821829Y-38304D01*
X820956Y-40346D01*
X820519Y-42096D01*
Y-43846D01*
X820956Y-45596D01*
X822048Y-47346D01*
X823358Y-48512D01*
X824886Y-48804D01*
X826414Y-48221D01*
X827943Y-46471D01*
G01X838674Y-48804D02*
Y-37138D01*
G01Y-39471D02*
X839766Y-38304D01*
X840858Y-37429D01*
X842386Y-37138D01*
X843477Y-37429D01*
X844788Y-38304D01*
G01X793614Y-76304D02*
Y-93804D01*
X802348D01*
G01X810678Y-90304D02*
X811987Y-92346D01*
X813734Y-93512D01*
X815699Y-93804D01*
X817446Y-93512D01*
X819193Y-92054D01*
X820284Y-90304D01*
X820503Y-88554D01*
X820066Y-86513D01*
X818538Y-85054D01*
X817009Y-84471D01*
X815044D01*
G01X817009D02*
X818319Y-83596D01*
X819411Y-82138D01*
X819848Y-80388D01*
X819411Y-78637D01*
X818319Y-77179D01*
X816354Y-76304D01*
X814389Y-76596D01*
X812424Y-77763D01*
G01X931781Y-93804D02*
X930034Y-93512D01*
X928506Y-92346D01*
X927196Y-90596D01*
X926322Y-88554D01*
X925886Y-86221D01*
Y-83887D01*
X926322Y-81554D01*
X927196Y-79512D01*
X928506Y-77763D01*
X930034Y-76596D01*
X931781Y-76304D01*
X933527Y-76596D01*
X935056Y-77763D01*
X936366Y-79512D01*
X937240Y-81554D01*
X937676Y-83887D01*
Y-86221D01*
X937240Y-88554D01*
X936366Y-90596D01*
X935056Y-92346D01*
X933527Y-93512D01*
X931781Y-93804D01*
G01X933527Y-89137D02*
X936148Y-93804D01*
G01X944478Y-76304D02*
Y-88846D01*
X945351Y-91471D01*
X947098Y-93221D01*
X949281Y-93804D01*
X951464Y-93221D01*
X953211Y-91471D01*
X954084Y-88846D01*
Y-76304D01*
G01X964161D02*
X969401D01*
G01X966781D02*
Y-93804D01*
G01X964161D02*
X969401D01*
G01X979259D02*
Y-76304D01*
X989303Y-93804D01*
Y-76304D01*
G01X1006584Y-77763D02*
X1005274Y-76887D01*
X1003746Y-76304D01*
X1001999D01*
X1000034Y-77179D01*
X998506Y-78637D01*
X997414Y-80388D01*
X996541Y-83304D01*
X996322Y-85929D01*
X996759Y-88554D01*
X997414Y-90304D01*
X998724Y-92054D01*
X1000253Y-93221D01*
X1001781Y-93804D01*
X1003309D01*
X1004838Y-93221D01*
X1006148Y-92346D01*
X1007240Y-91180D01*
G01X1019281Y-93804D02*
Y-85929D01*
X1014914Y-76304D01*
G01X1023648D02*
X1019281Y-85929D01*
G01X909478Y-48804D02*
Y-31304D01*
X913844D01*
X915591Y-32179D01*
X916901Y-33346D01*
X917993Y-35095D01*
X918866Y-37138D01*
X919084Y-40054D01*
X918866Y-42971D01*
X917993Y-45013D01*
X916901Y-46763D01*
X915591Y-47929D01*
X913844Y-48804D01*
X909478D01*
G01X928506Y-40929D02*
X935493D01*
X934838Y-38887D01*
X933746Y-37721D01*
X932218Y-37138D01*
X930689Y-37429D01*
X929379Y-38304D01*
X928506Y-40346D01*
X928069Y-42096D01*
Y-43846D01*
X928506Y-45596D01*
X929598Y-47346D01*
X930908Y-48512D01*
X932436Y-48804D01*
X933964Y-48221D01*
X935493Y-46471D01*
G01X946006Y-46763D02*
X947098Y-47929D01*
X948626Y-48804D01*
X949936D01*
X951246Y-48221D01*
X952119Y-47346D01*
X952556Y-46180D01*
X952338Y-44429D01*
X951464Y-43554D01*
X947534Y-41804D01*
X946661Y-39762D01*
X947098Y-38304D01*
X947971Y-37429D01*
X949281Y-37138D01*
X950591Y-37429D01*
X951901Y-38304D01*
G01X966781Y-37138D02*
Y-48804D01*
G01Y-32471D02*
X966344Y-32179D01*
Y-31596D01*
X966781Y-31304D01*
X967218Y-31596D01*
Y-32179D01*
X966781Y-32471D01*
G01X981224Y-53179D02*
X982753Y-54346D01*
X984499Y-54637D01*
X986027Y-54346D01*
X987338Y-52888D01*
X988211Y-50846D01*
Y-37138D01*
G01Y-39471D02*
X987338Y-38304D01*
X986027Y-37429D01*
X984499Y-37138D01*
X982753Y-37721D01*
X981661Y-38887D01*
X980787Y-40929D01*
X980351Y-42971D01*
X980569Y-44721D01*
X981443Y-46763D01*
X982753Y-48221D01*
X984499Y-48804D01*
X985809Y-48512D01*
X987338Y-47346D01*
X988211Y-46180D01*
G01X998069Y-48804D02*
Y-37138D01*
G01Y-40054D02*
X998943Y-38596D01*
X1000253Y-37429D01*
X1001999Y-37138D01*
X1003527Y-37429D01*
X1004838Y-38596D01*
X1005493Y-40637D01*
Y-48804D01*
G01X1016006Y-40929D02*
X1022993D01*
X1022338Y-38887D01*
X1021246Y-37721D01*
X1019718Y-37138D01*
X1018189Y-37429D01*
X1016879Y-38304D01*
X1016006Y-40346D01*
X1015569Y-42096D01*
Y-43846D01*
X1016006Y-45596D01*
X1017098Y-47346D01*
X1018408Y-48512D01*
X1019936Y-48804D01*
X1021464Y-48221D01*
X1022993Y-46471D01*
G01X1033724Y-48804D02*
Y-37138D01*
G01Y-39471D02*
X1034816Y-38304D01*
X1035908Y-37429D01*
X1037436Y-37138D01*
X1038527Y-37429D01*
X1039838Y-38304D01*
G01X1080481Y-76304D02*
X1078734Y-76887D01*
X1077424Y-78346D01*
X1076551Y-80095D01*
X1075896Y-82429D01*
X1075678Y-85054D01*
X1075896Y-87679D01*
X1076551Y-90013D01*
X1077424Y-91763D01*
X1078734Y-93221D01*
X1080481Y-93804D01*
X1082227Y-93221D01*
X1083538Y-91763D01*
X1084411Y-90013D01*
X1085066Y-87679D01*
X1085284Y-85054D01*
X1085066Y-82429D01*
X1084411Y-80095D01*
X1083538Y-78346D01*
X1082227Y-76887D01*
X1080481Y-76304D01*
G01X1097981Y-93804D02*
X1099509Y-93512D01*
X1101256Y-92638D01*
X1102348Y-91180D01*
X1102784Y-89137D01*
X1102348Y-87096D01*
X1101038Y-85346D01*
X1099073Y-84471D01*
X1096889D01*
X1095579Y-83887D01*
X1094487Y-82429D01*
X1094051Y-80388D01*
X1094706Y-78346D01*
X1096234Y-76887D01*
X1097981Y-76304D01*
X1099727Y-76887D01*
X1101256Y-78346D01*
X1101911Y-80388D01*
X1101474Y-82429D01*
X1100383Y-83887D01*
X1099073Y-84471D01*
X1096889D01*
X1094924Y-85346D01*
X1093614Y-87096D01*
X1093178Y-89137D01*
X1093614Y-91180D01*
X1094706Y-92638D01*
X1096453Y-93512D01*
X1097981Y-93804D01*
G01X1111551Y-94387D02*
X1119411Y-76304D01*
G01X1132981D02*
X1131234Y-76887D01*
X1129924Y-78346D01*
X1129051Y-80095D01*
X1128396Y-82429D01*
X1128178Y-85054D01*
X1128396Y-87679D01*
X1129051Y-90013D01*
X1129924Y-91763D01*
X1131234Y-93221D01*
X1132981Y-93804D01*
X1134727Y-93221D01*
X1136038Y-91763D01*
X1136911Y-90013D01*
X1137566Y-87679D01*
X1137784Y-85054D01*
X1137566Y-82429D01*
X1136911Y-80095D01*
X1136038Y-78346D01*
X1134727Y-76887D01*
X1132981Y-76304D01*
G01X1150044Y-93804D02*
X1150481Y-90013D01*
X1151136Y-86804D01*
X1152009Y-83887D01*
X1153101Y-80679D01*
X1154848Y-76304D01*
X1146114D01*
G01X1164051Y-94387D02*
X1171911Y-76304D01*
G01X1181333Y-79221D02*
X1182643Y-77471D01*
X1184171Y-76596D01*
X1185918Y-76304D01*
X1188101Y-76887D01*
X1189629Y-78346D01*
X1190066Y-80095D01*
X1189848Y-81846D01*
X1188974Y-83304D01*
X1184608Y-86221D01*
X1182643Y-88262D01*
X1181333Y-91180D01*
X1180896Y-93804D01*
X1190066D01*
G01X1202981Y-76304D02*
X1201234Y-76887D01*
X1199924Y-78346D01*
X1199051Y-80095D01*
X1198396Y-82429D01*
X1198178Y-85054D01*
X1198396Y-87679D01*
X1199051Y-90013D01*
X1199924Y-91763D01*
X1201234Y-93221D01*
X1202981Y-93804D01*
X1204727Y-93221D01*
X1206038Y-91763D01*
X1206911Y-90013D01*
X1207566Y-87679D01*
X1207784Y-85054D01*
X1207566Y-82429D01*
X1206911Y-80095D01*
X1206038Y-78346D01*
X1204727Y-76887D01*
X1202981Y-76304D01*
G01X1220481Y-93804D02*
Y-76304D01*
X1217861Y-79804D01*
G01Y-93804D02*
X1223101D01*
G01X1237544D02*
X1237981Y-90013D01*
X1238636Y-86804D01*
X1239509Y-83887D01*
X1240601Y-80679D01*
X1242348Y-76304D01*
X1233614D01*
G01X1128178Y-48804D02*
Y-31304D01*
X1132544D01*
X1134291Y-32179D01*
X1135601Y-33346D01*
X1136693Y-35095D01*
X1137566Y-37138D01*
X1137784Y-40054D01*
X1137566Y-42971D01*
X1136693Y-45013D01*
X1135601Y-46763D01*
X1134291Y-47929D01*
X1132544Y-48804D01*
X1128178D01*
G01X1154411D02*
Y-37138D01*
G01Y-39179D02*
X1153538Y-38013D01*
X1152227Y-37429D01*
X1150699Y-37138D01*
X1149171Y-37721D01*
X1147861Y-38887D01*
X1146987Y-40637D01*
X1146551Y-42971D01*
X1146987Y-45304D01*
X1147861Y-47054D01*
X1149171Y-48221D01*
X1150699Y-48804D01*
X1152227Y-48512D01*
X1153538Y-47638D01*
X1154411Y-46471D01*
G01X1167981Y-31304D02*
Y-48804D01*
G01X1164924Y-37138D02*
X1171038D01*
G01X1182206Y-40929D02*
X1189193D01*
X1188538Y-38887D01*
X1187446Y-37721D01*
X1185918Y-37138D01*
X1184389Y-37429D01*
X1183079Y-38304D01*
X1182206Y-40346D01*
X1181769Y-42096D01*
Y-43846D01*
X1182206Y-45596D01*
X1183298Y-47346D01*
X1184608Y-48512D01*
X1186136Y-48804D01*
X1187664Y-48221D01*
X1189193Y-46471D01*
G54D15*
X428740Y154331D03*
X421653Y164567D03*
Y173229D03*
Y178740D03*
X428740Y174016D03*
X457086Y154331D03*
X471260D03*
X442913Y159843D03*
X450000Y164567D03*
X457086Y159843D03*
X471260D03*
X457086Y168504D03*
X464173Y173229D03*
X442913Y174016D03*
X457086D03*
X464173Y178740D03*
X513779Y154331D03*
X520866Y159055D03*
X535039D03*
X542126Y154331D03*
X513779Y159843D03*
X520866Y164567D03*
X527953Y159843D03*
X535039Y164567D03*
X542126Y159843D03*
X556299D03*
X520866Y173229D03*
X549212D03*
X520866Y178740D03*
X535039D03*
X549212D03*
G54D25*
G01X195600Y646000D02*
X202913Y638687D01*
Y632713D01*
X201350Y631150D01*
Y622850D01*
X201700Y622500D01*
Y611900D01*
X195900Y606100D01*
Y598685D01*
X194093Y596878D01*
Y596063D01*
G54D16*
X556299Y179528D03*
G54D26*
G01X86750Y539218D02*
X88325Y540793D01*
X91461D01*
G01X91687Y553767D02*
X91310Y553390D01*
X85173D01*
X83600Y551817D01*
G01Y564415D02*
X85175Y562840D01*
X91272D01*
X91287Y562855D01*
G01X92377Y565977D02*
X90565D01*
X90552Y565990D01*
X88325D01*
X86750Y564415D01*
G54D17*
G01X33464Y34449D02*
X61024D01*
G01X80708Y44292D02*
X108268D01*
G01X162100Y711215D02*
X159417D01*
X154764Y706562D01*
Y700848D01*
X152004Y698088D01*
X141284D01*
X134223Y691027D01*
G01X199600Y646300D02*
Y651700D01*
X195500Y655800D01*
Y696900D01*
G01X277455Y446150D02*
X278551Y445054D01*
X284365D01*
X284366Y445053D01*
X286940D01*
X305693Y426300D01*
X305694D01*
X306944Y425050D01*
X321044D01*
X325047Y421047D01*
X327100Y418995D01*
Y408164D01*
X312878Y393942D01*
Y380695D01*
X309270Y377087D01*
Y369655D01*
X311426Y367499D01*
X315720D01*
X319332Y363887D01*
Y274100D01*
X312200Y266968D01*
Y262264D01*
X306375Y256439D01*
X305542D01*
X299900Y250797D01*
Y190818D01*
X303744Y186974D01*
X311684D01*
X318000Y180658D01*
Y134400D01*
X316494Y132894D01*
Y36419D01*
X327519Y25394D01*
X365556D01*
X377001Y13949D01*
X378863D01*
X378864Y13950D01*
X568715D01*
X582797Y28032D01*
Y31807D01*
G01X265400Y446100D02*
Y448628D01*
X263514Y450514D01*
X260200Y453829D01*
Y474644D01*
X259609Y475235D01*
Y500081D01*
X260850Y501322D01*
Y541626D01*
X254599Y547877D01*
Y555817D01*
X252216Y558200D01*
Y574229D01*
X255137Y577150D01*
X256819D01*
X264425Y584756D01*
Y591442D01*
X267000Y594017D01*
Y608499D01*
X265458Y610041D01*
Y624058D01*
X273323Y631923D01*
Y651523D01*
X273550Y651750D01*
Y651786D01*
X279000Y657236D01*
Y669330D01*
X280700Y671030D01*
Y681400D01*
X267045Y695055D01*
Y695881D01*
G01X588753Y24080D02*
X575973Y11300D01*
X376114D01*
X364520Y22894D01*
X326483D01*
X313993Y35384D01*
Y37454D01*
X313994Y37455D01*
Y134906D01*
X300301Y148599D01*
Y186881D01*
X296600Y190582D01*
Y251033D01*
X297400Y251833D01*
Y251834D01*
X298863Y253297D01*
X298864D01*
X304575Y259008D01*
X305377D01*
X309700Y263331D01*
Y361800D01*
X306750Y364750D01*
Y378103D01*
X310378Y381731D01*
Y394978D01*
X324600Y409200D01*
Y417958D01*
X320008Y422550D01*
X305550D01*
X285547Y442553D01*
X283330D01*
X283329Y442554D01*
X275011D01*
X262700Y454865D01*
Y475680D01*
X262109Y476271D01*
Y499045D01*
X263350Y500286D01*
Y510950D01*
X265700Y513300D01*
Y544500D01*
X264100Y546100D01*
X261005D01*
X257946Y549159D01*
Y556835D01*
X254716Y560065D01*
Y569319D01*
X264100Y578703D01*
Y580538D01*
X264120Y580558D01*
Y580915D01*
X268187Y584982D01*
Y591387D01*
X284494Y607694D01*
Y621006D01*
X276050Y629450D01*
Y650750D01*
X281620Y656320D01*
Y668414D01*
X286294Y673088D01*
Y684174D01*
X274150Y696318D01*
Y708220D01*
X292630Y726700D01*
X292975D01*
X293075Y726600D01*
G01X848868Y219064D02*
X847268Y217464D01*
Y58024D01*
X825311Y36067D01*
X788590D01*
X778223Y25700D01*
X699200D01*
X686350Y12850D01*
X582250D01*
X578156Y8756D01*
X375122D01*
X363484Y20394D01*
X325447D01*
X311493Y34348D01*
Y38490D01*
X311494Y38491D01*
Y133706D01*
X297800Y147400D01*
Y185846D01*
X294100Y189546D01*
Y254800D01*
X301900Y262600D01*
Y370600D01*
X294063Y378437D01*
Y425663D01*
X295700Y427300D01*
Y428400D01*
G01X334000Y714640D02*
X334924Y713716D01*
Y667624D01*
X333800Y666500D01*
Y651836D01*
X323100Y641136D01*
Y631600D01*
X313750Y622250D01*
Y593472D01*
X313642Y593364D01*
Y585610D01*
X313215Y585183D01*
Y566016D01*
X317909Y561322D01*
Y542562D01*
X315200Y539853D01*
Y527700D01*
X313300Y525800D01*
Y518800D01*
G01X441100Y110950D02*
X440896Y111154D01*
X417781D01*
X406803Y122132D01*
Y144798D01*
X403794Y147807D01*
Y150895D01*
X407300Y154401D01*
Y160118D01*
X387750Y179668D01*
Y316750D01*
X386250Y318250D01*
G01X567700Y28240D02*
X567710Y28250D01*
Y69173D01*
X644090Y145553D01*
Y395759D01*
X669749Y421418D01*
Y458022D01*
G54D27*
G01X341755Y627231D02*
X340624Y626100D01*
X339245D01*
X337639Y624494D01*
Y608751D01*
X344300Y602090D01*
Y599441D01*
X339400Y594541D01*
Y579386D01*
X336944Y576930D01*
Y553035D01*
X343175Y546804D01*
Y528877D01*
X342743Y528445D01*
Y518244D01*
X341425Y516926D01*
Y492560D01*
X347275Y486710D01*
Y452564D01*
X347626Y452213D01*
Y446427D01*
X349767Y444286D01*
Y439570D01*
X357975Y431362D01*
Y391214D01*
X355575Y388814D01*
Y376558D01*
X353325Y374308D01*
Y369761D01*
X353925Y369161D01*
Y212193D01*
X348525Y206793D01*
Y182436D01*
X352025Y178936D01*
Y122155D01*
X388651Y85529D01*
Y83748D01*
X387833Y82930D01*
G01X341755Y623682D02*
X340637Y624800D01*
X339784D01*
X338939Y623955D01*
Y609290D01*
X345600Y602629D01*
Y598902D01*
X340700Y594002D01*
Y578847D01*
X338244Y576391D01*
Y553574D01*
X344475Y547343D01*
Y528338D01*
X344043Y527906D01*
Y517705D01*
X342725Y516387D01*
Y493099D01*
X348575Y487249D01*
Y453103D01*
X348926Y452752D01*
Y446966D01*
X351067Y444825D01*
Y440109D01*
X359275Y431901D01*
Y390675D01*
X356875Y388275D01*
Y376019D01*
X354625Y373769D01*
Y370300D01*
X355225Y369700D01*
Y211654D01*
X349825Y206254D01*
Y182975D01*
X353325Y179475D01*
Y169258D01*
X354025Y168558D01*
Y166908D01*
X353325Y166208D01*
Y164558D01*
X354025Y163858D01*
Y162208D01*
X353325Y161508D01*
Y159858D01*
X354025Y159158D01*
Y157508D01*
X353325Y156808D01*
Y122694D01*
X389951Y86068D01*
Y84361D01*
X391382Y82930D01*
G54D18*
G01X159412Y552006D02*
X161578Y554172D01*
X163566D01*
X165748Y551990D01*
Y551968D01*
G54D28*
G01X122600Y557480D02*
X120480Y555360D01*
X113410D01*
X107395Y549345D01*
G54D19*
G01X53302Y567317D02*
X57687Y562932D01*
Y523067D01*
X63237Y517517D01*
X99750D01*
X102652Y520419D01*
Y525557D01*
X96371Y531838D01*
Y534124D01*
G01X58926Y582407D02*
X53302Y576783D01*
Y567317D01*
M02*
